FILE_TYPE=LIBRARY_PARTS;
primitive 'LCMXO3LF9400C5BG484C';
  pin
    'PL2A':
      PIN_NUMBER='(D3,0,0,0,0,0,0)';
      BIDIRECTIONAL='TRUE';
      INPUT_LOAD='(-0.01,0.01)';
      OUTPUT_LOAD='(1.0,-1.0)';
    'PL2B':
      PIN_NUMBER='(D4,0,0,0,0,0,0)';
      BIDIRECTIONAL='TRUE';
      INPUT_LOAD='(-0.01,0.01)';
      OUTPUT_LOAD='(1.0,-1.0)';
    'PL2C':
      PIN_NUMBER='(F6,0,0,0,0,0,0)';
      BIDIRECTIONAL='TRUE';
      INPUT_LOAD='(-0.01,0.01)';
      OUTPUT_LOAD='(1.0,-1.0)';
    'PL2D':
      PIN_NUMBER='(G7,0,0,0,0,0,0)';
      BIDIRECTIONAL='TRUE';
      INPUT_LOAD='(-0.01,0.01)';
      OUTPUT_LOAD='(1.0,-1.0)';
    'PL3A||L_GPLLT_FB':
      PIN_NUMBER='(E4,0,0,0,0,0,0)';
      BIDIRECTIONAL='TRUE';
      INPUT_LOAD='(-0.01,0.01)';
      OUTPUT_LOAD='(1.0,-1.0)';
    'PL3B||L_GPLLC_FB':
      PIN_NUMBER='(F5,0,0,0,0,0,0)';
      BIDIRECTIONAL='TRUE';
      INPUT_LOAD='(-0.01,0.01)';
      OUTPUT_LOAD='(1.0,-1.0)';
    'PL3C':
      PIN_NUMBER='(G6,0,0,0,0,0,0)';
      BIDIRECTIONAL='TRUE';
      INPUT_LOAD='(-0.01,0.01)';
      OUTPUT_LOAD='(1.0,-1.0)';
    'PL3D':
      PIN_NUMBER='(H7,0,0,0,0,0,0)';
      BIDIRECTIONAL='TRUE';
      INPUT_LOAD='(-0.01,0.01)';
      OUTPUT_LOAD='(1.0,-1.0)';
    'PL4A||L_GPLLT_IN':
      PIN_NUMBER='(C1,0,0,0,0,0,0)';
      BIDIRECTIONAL='TRUE';
      INPUT_LOAD='(-0.01,0.01)';
      OUTPUT_LOAD='(1.0,-1.0)';
    'PL4B||L_GPLLC_IN':
      PIN_NUMBER='(D2,0,0,0,0,0,0)';
      BIDIRECTIONAL='TRUE';
      INPUT_LOAD='(-0.01,0.01)';
      OUTPUT_LOAD='(1.0,-1.0)';
    'PL4C':
      PIN_NUMBER='(G5,0,0,0,0,0,0)';
      BIDIRECTIONAL='TRUE';
      INPUT_LOAD='(-0.01,0.01)';
      OUTPUT_LOAD='(1.0,-1.0)';
    'PL4D':
      PIN_NUMBER='(H6,0,0,0,0,0,0)';
      BIDIRECTIONAL='TRUE';
      INPUT_LOAD='(-0.01,0.01)';
      OUTPUT_LOAD='(1.0,-1.0)';
    'PL5A':
      PIN_NUMBER='(D1,0,0,0,0,0,0)';
      BIDIRECTIONAL='TRUE';
      INPUT_LOAD='(-0.01,0.01)';
      OUTPUT_LOAD='(1.0,-1.0)';
    'PL5B':
      PIN_NUMBER='(E2,0,0,0,0,0,0)';
      BIDIRECTIONAL='TRUE';
      INPUT_LOAD='(-0.01,0.01)';
      OUTPUT_LOAD='(1.0,-1.0)';
    'PL5C':
      PIN_NUMBER='(E3,0,0,0,0,0,0)';
      BIDIRECTIONAL='TRUE';
      INPUT_LOAD='(-0.01,0.01)';
      OUTPUT_LOAD='(1.0,-1.0)';
    'PL5D':
      PIN_NUMBER='(F4,0,0,0,0,0,0)';
      BIDIRECTIONAL='TRUE';
      INPUT_LOAD='(-0.01,0.01)';
      OUTPUT_LOAD='(1.0,-1.0)';
    'PL13A':
      PIN_NUMBER='(L7,0,0,0,0,0,0)';
      BIDIRECTIONAL='TRUE';
      INPUT_LOAD='(-0.01,0.01)';
      OUTPUT_LOAD='(1.0,-1.0)';
    'PL13B':
      PIN_NUMBER='(K5,0,0,0,0,0,0)';
      BIDIRECTIONAL='TRUE';
      INPUT_LOAD='(-0.01,0.01)';
      OUTPUT_LOAD='(1.0,-1.0)';
    'PL13C':
      PIN_NUMBER='(K4,0,0,0,0,0,0)';
      BIDIRECTIONAL='TRUE';
      INPUT_LOAD='(-0.01,0.01)';
      OUTPUT_LOAD='(1.0,-1.0)';
    'PL13D':
      PIN_NUMBER='(K3,0,0,0,0,0,0)';
      BIDIRECTIONAL='TRUE';
      INPUT_LOAD='(-0.01,0.01)';
      OUTPUT_LOAD='(1.0,-1.0)';
    'PL14A':
      PIN_NUMBER='(K2,0,0,0,0,0,0)';
      BIDIRECTIONAL='TRUE';
      INPUT_LOAD='(-0.01,0.01)';
      OUTPUT_LOAD='(1.0,-1.0)';
    'PL14B':
      PIN_NUMBER='(K1,0,0,0,0,0,0)';
      BIDIRECTIONAL='TRUE';
      INPUT_LOAD='(-0.01,0.01)';
      OUTPUT_LOAD='(1.0,-1.0)';
    'PL16A||PCLKT4_0':
      PIN_NUMBER='(L1,0,0,0,0,0,0)';
      BIDIRECTIONAL='TRUE';
      INPUT_LOAD='(-0.01,0.01)';
      OUTPUT_LOAD='(1.0,-1.0)';
    'PL16B||PCLKC4_0':
      PIN_NUMBER='(M2,0,0,0,0,0,0)';
      BIDIRECTIONAL='TRUE';
      INPUT_LOAD='(-0.01,0.01)';
      OUTPUT_LOAD='(1.0,-1.0)';
    'PL20A':
      PIN_NUMBER='(P4,0,0,0,0,0,0)';
      BIDIRECTIONAL='TRUE';
      INPUT_LOAD='(-0.01,0.01)';
      OUTPUT_LOAD='(1.0,-1.0)';
    'PL20B':
      PIN_NUMBER='(N5,0,0,0,0,0,0)';
      BIDIRECTIONAL='TRUE';
      INPUT_LOAD='(-0.01,0.01)';
      OUTPUT_LOAD='(1.0,-1.0)';
    'PL20C':
      PIN_NUMBER='(N6,0,0,0,0,0,0)';
      BIDIRECTIONAL='TRUE';
      INPUT_LOAD='(-0.01,0.01)';
      OUTPUT_LOAD='(1.0,-1.0)';
    'PL20D':
      PIN_NUMBER='(N7,0,0,0,0,0,0)';
      BIDIRECTIONAL='TRUE';
      INPUT_LOAD='(-0.01,0.01)';
      OUTPUT_LOAD='(1.0,-1.0)';
    'PL21A':
      PIN_NUMBER='(R2,0,0,0,0,0,0)';
      BIDIRECTIONAL='TRUE';
      INPUT_LOAD='(-0.01,0.01)';
      OUTPUT_LOAD='(1.0,-1.0)';
    'PL21B':
      PIN_NUMBER='(T1,0,0,0,0,0,0)';
      BIDIRECTIONAL='TRUE';
      INPUT_LOAD='(-0.01,0.01)';
      OUTPUT_LOAD='(1.0,-1.0)';
    'PL21C':
      PIN_NUMBER='(P5,0,0,0,0,0,0)';
      BIDIRECTIONAL='TRUE';
      INPUT_LOAD='(-0.01,0.01)';
      OUTPUT_LOAD='(1.0,-1.0)';
    'PL21D':
      PIN_NUMBER='(P6,0,0,0,0,0,0)';
      BIDIRECTIONAL='TRUE';
      INPUT_LOAD='(-0.01,0.01)';
      OUTPUT_LOAD='(1.0,-1.0)';
    'PL26C':
      PIN_NUMBER='(T5,0,0,0,0,0,0)';
      BIDIRECTIONAL='TRUE';
      INPUT_LOAD='(-0.01,0.01)';
      OUTPUT_LOAD='(1.0,-1.0)';
    'PL26D':
      PIN_NUMBER='(T6,0,0,0,0,0,0)';
      BIDIRECTIONAL='TRUE';
      INPUT_LOAD='(-0.01,0.01)';
      OUTPUT_LOAD='(1.0,-1.0)';
    'PL14C':
      PIN_NUMBER='(L6,0,0,0,0,0,0)';
      BIDIRECTIONAL='TRUE';
      INPUT_LOAD='(-0.01,0.01)';
      OUTPUT_LOAD='(1.0,-1.0)';
    'PL14D':
      PIN_NUMBER='(L5,0,0,0,0,0,0)';
      BIDIRECTIONAL='TRUE';
      INPUT_LOAD='(-0.01,0.01)';
      OUTPUT_LOAD='(1.0,-1.0)';
    'PL16C':
      PIN_NUMBER='(L3,0,0,0,0,0,0)';
      BIDIRECTIONAL='TRUE';
      INPUT_LOAD='(-0.01,0.01)';
      OUTPUT_LOAD='(1.0,-1.0)';
    'PL16D':
      PIN_NUMBER='(L4,0,0,0,0,0,0)';
      BIDIRECTIONAL='TRUE';
      INPUT_LOAD='(-0.01,0.01)';
      OUTPUT_LOAD='(1.0,-1.0)';
    'PL6C':
      PIN_NUMBER='(G3,0,0,0,0,0,0)';
      BIDIRECTIONAL='TRUE';
      INPUT_LOAD='(-0.01,0.01)';
      OUTPUT_LOAD='(1.0,-1.0)';
    'PL6D':
      PIN_NUMBER='(G4,0,0,0,0,0,0)';
      BIDIRECTIONAL='TRUE';
      INPUT_LOAD='(-0.01,0.01)';
      OUTPUT_LOAD='(1.0,-1.0)';
    'PL6A':
      PIN_NUMBER='(E1,0,0,0,0,0,0)';
      BIDIRECTIONAL='TRUE';
      INPUT_LOAD='(-0.01,0.01)';
      OUTPUT_LOAD='(1.0,-1.0)';
    'PL6B':
      PIN_NUMBER='(F1,0,0,0,0,0,0)';
      BIDIRECTIONAL='TRUE';
      INPUT_LOAD='(-0.01,0.01)';
      OUTPUT_LOAD='(1.0,-1.0)';
    'PL25A':
      PIN_NUMBER='(T2,0,0,0,0,0,0)';
      BIDIRECTIONAL='TRUE';
      INPUT_LOAD='(-0.01,0.01)';
      OUTPUT_LOAD='(1.0,-1.0)';
    'PL25B':
      PIN_NUMBER='(U1,0,0,0,0,0,0)';
      BIDIRECTIONAL='TRUE';
      INPUT_LOAD='(-0.01,0.01)';
      OUTPUT_LOAD='(1.0,-1.0)';
    'PL24A':
      PIN_NUMBER='(R3,0,0,0,0,0,0)';
      BIDIRECTIONAL='TRUE';
      INPUT_LOAD='(-0.01,0.01)';
      OUTPUT_LOAD='(1.0,-1.0)';
    'PL24B':
      PIN_NUMBER='(R4,0,0,0,0,0,0)';
      BIDIRECTIONAL='TRUE';
      INPUT_LOAD='(-0.01,0.01)';
      OUTPUT_LOAD='(1.0,-1.0)';
    'PL24C':
      PIN_NUMBER='(R5,0,0,0,0,0,0)';
      BIDIRECTIONAL='TRUE';
      INPUT_LOAD='(-0.01,0.01)';
      OUTPUT_LOAD='(1.0,-1.0)';
    'PL24D':
      PIN_NUMBER='(P7,0,0,0,0,0,0)';
      BIDIRECTIONAL='TRUE';
      INPUT_LOAD='(-0.01,0.01)';
      OUTPUT_LOAD='(1.0,-1.0)';
    'PL25C':
      PIN_NUMBER='(R6,0,0,0,0,0,0)';
      BIDIRECTIONAL='TRUE';
      INPUT_LOAD='(-0.01,0.01)';
      OUTPUT_LOAD='(1.0,-1.0)';
    'PL25D':
      PIN_NUMBER='(R7,0,0,0,0,0,0)';
      BIDIRECTIONAL='TRUE';
      INPUT_LOAD='(-0.01,0.01)';
      OUTPUT_LOAD='(1.0,-1.0)';
    'PL26A':
      PIN_NUMBER='(T3,0,0,0,0,0,0)';
      BIDIRECTIONAL='TRUE';
      INPUT_LOAD='(-0.01,0.01)';
      OUTPUT_LOAD='(1.0,-1.0)';
    'PL26B':
      PIN_NUMBER='(T4,0,0,0,0,0,0)';
      BIDIRECTIONAL='TRUE';
      INPUT_LOAD='(-0.01,0.01)';
      OUTPUT_LOAD='(1.0,-1.0)';
    'PL17A':
      PIN_NUMBER='(M1,0,0,0,0,0,0)';
      BIDIRECTIONAL='TRUE';
      INPUT_LOAD='(-0.01,0.01)';
      OUTPUT_LOAD='(1.0,-1.0)';
    'PL17B':
      PIN_NUMBER='(N1,0,0,0,0,0,0)';
      BIDIRECTIONAL='TRUE';
      INPUT_LOAD='(-0.01,0.01)';
      OUTPUT_LOAD='(1.0,-1.0)';
    'PL17C':
      PIN_NUMBER='(M6,0,0,0,0,0,0)';
      BIDIRECTIONAL='TRUE';
      INPUT_LOAD='(-0.01,0.01)';
      OUTPUT_LOAD='(1.0,-1.0)';
    'PL17D':
      PIN_NUMBER='(M5,0,0,0,0,0,0)';
      BIDIRECTIONAL='TRUE';
      INPUT_LOAD='(-0.01,0.01)';
      OUTPUT_LOAD='(1.0,-1.0)';
    'PL18A':
      PIN_NUMBER='(N2,0,0,0,0,0,0)';
      BIDIRECTIONAL='TRUE';
      INPUT_LOAD='(-0.01,0.01)';
      OUTPUT_LOAD='(1.0,-1.0)';
    'PL18B':
      PIN_NUMBER='(P1,0,0,0,0,0,0)';
      BIDIRECTIONAL='TRUE';
      INPUT_LOAD='(-0.01,0.01)';
      OUTPUT_LOAD='(1.0,-1.0)';
    'PL18C':
      PIN_NUMBER='(N3,0,0,0,0,0,0)';
      BIDIRECTIONAL='TRUE';
      INPUT_LOAD='(-0.01,0.01)';
      OUTPUT_LOAD='(1.0,-1.0)';
    'PL18D':
      PIN_NUMBER='(N4,0,0,0,0,0,0)';
      BIDIRECTIONAL='TRUE';
      INPUT_LOAD='(-0.01,0.01)';
      OUTPUT_LOAD='(1.0,-1.0)';
    'PL19A':
      PIN_NUMBER='(P2,0,0,0,0,0,0)';
      BIDIRECTIONAL='TRUE';
      INPUT_LOAD='(-0.01,0.01)';
      OUTPUT_LOAD='(1.0,-1.0)';
    'PL19B':
      PIN_NUMBER='(R1,0,0,0,0,0,0)';
      BIDIRECTIONAL='TRUE';
      INPUT_LOAD='(-0.01,0.01)';
      OUTPUT_LOAD='(1.0,-1.0)';
    'PL19C':
      PIN_NUMBER='(P3,0,0,0,0,0,0)';
      BIDIRECTIONAL='TRUE';
      INPUT_LOAD='(-0.01,0.01)';
      OUTPUT_LOAD='(1.0,-1.0)';
    'PL19D':
      PIN_NUMBER='(M7,0,0,0,0,0,0)';
      BIDIRECTIONAL='TRUE';
      INPUT_LOAD='(-0.01,0.01)';
      OUTPUT_LOAD='(1.0,-1.0)';
    'PL27A||PCLKT3_0':
      PIN_NUMBER='(U2,0,0,0,0,0,0)';
      BIDIRECTIONAL='TRUE';
      INPUT_LOAD='(-0.01,0.01)';
      OUTPUT_LOAD='(1.0,-1.0)';
    'PL27B||PCLKC3_0':
      PIN_NUMBER='(V1,0,0,0,0,0,0)';
      BIDIRECTIONAL='TRUE';
      INPUT_LOAD='(-0.01,0.01)';
      OUTPUT_LOAD='(1.0,-1.0)';
    'PL27C':
      PIN_NUMBER='(U3,0,0,0,0,0,0)';
      BIDIRECTIONAL='TRUE';
      INPUT_LOAD='(-0.01,0.01)';
      OUTPUT_LOAD='(1.0,-1.0)';
    'PL27D':
      PIN_NUMBER='(U4,0,0,0,0,0,0)';
      BIDIRECTIONAL='TRUE';
      INPUT_LOAD='(-0.01,0.01)';
      OUTPUT_LOAD='(1.0,-1.0)';
    'PL28A':
      PIN_NUMBER='(W1,0,0,0,0,0,0)';
      BIDIRECTIONAL='TRUE';
      INPUT_LOAD='(-0.01,0.01)';
      OUTPUT_LOAD='(1.0,-1.0)';
    'PL28B':
      PIN_NUMBER='(W2,0,0,0,0,0,0)';
      BIDIRECTIONAL='TRUE';
      INPUT_LOAD='(-0.01,0.01)';
      OUTPUT_LOAD='(1.0,-1.0)';
    'PL28C':
      PIN_NUMBER='(V4,0,0,0,0,0,0)';
      BIDIRECTIONAL='TRUE';
      INPUT_LOAD='(-0.01,0.01)';
      OUTPUT_LOAD='(1.0,-1.0)';
    'PL28D':
      PIN_NUMBER='(U5,0,0,0,0,0,0)';
      BIDIRECTIONAL='TRUE';
      INPUT_LOAD='(-0.01,0.01)';
      OUTPUT_LOAD='(1.0,-1.0)';
    'PL29A':
      PIN_NUMBER='(Y1,0,0,0,0,0,0)';
      BIDIRECTIONAL='TRUE';
      INPUT_LOAD='(-0.01,0.01)';
      OUTPUT_LOAD='(1.0,-1.0)';
    'PL29B':
      PIN_NUMBER='(AA1,0,0,0,0,0,0)';
      BIDIRECTIONAL='TRUE';
      INPUT_LOAD='(-0.01,0.01)';
      OUTPUT_LOAD='(1.0,-1.0)';
    'PL29C':
      PIN_NUMBER='(W3,0,0,0,0,0,0)';
      BIDIRECTIONAL='TRUE';
      INPUT_LOAD='(-0.01,0.01)';
      OUTPUT_LOAD='(1.0,-1.0)';
    'PL29D':
      PIN_NUMBER='(Y2,0,0,0,0,0,0)';
      BIDIRECTIONAL='TRUE';
      INPUT_LOAD='(-0.01,0.01)';
      OUTPUT_LOAD='(1.0,-1.0)';
    'PL30A':
      PIN_NUMBER='(Y3,0,0,0,0,0,0)';
      BIDIRECTIONAL='TRUE';
      INPUT_LOAD='(-0.01,0.01)';
      OUTPUT_LOAD='(1.0,-1.0)';
    'PL30B':
      PIN_NUMBER='(W4,0,0,0,0,0,0)';
      BIDIRECTIONAL='TRUE';
      INPUT_LOAD='(-0.01,0.01)';
      OUTPUT_LOAD='(1.0,-1.0)';
    'PL30C':
      PIN_NUMBER='(V5,0,0,0,0,0,0)';
      BIDIRECTIONAL='TRUE';
      INPUT_LOAD='(-0.01,0.01)';
      OUTPUT_LOAD='(1.0,-1.0)';
    'PL30D':
      PIN_NUMBER='(T7,0,0,0,0,0,0)';
      BIDIRECTIONAL='TRUE';
      INPUT_LOAD='(-0.01,0.01)';
      OUTPUT_LOAD='(1.0,-1.0)';
    'PL7A||PCLKT5_0':
      PIN_NUMBER='(G2,0,0,0,0,0,0)';
      BIDIRECTIONAL='TRUE';
      INPUT_LOAD='(-0.01,0.01)';
      OUTPUT_LOAD='(1.0,-1.0)';
    'PL7B||PCLKC5_0':
      PIN_NUMBER='(G1,0,0,0,0,0,0)';
      BIDIRECTIONAL='TRUE';
      INPUT_LOAD='(-0.01,0.01)';
      OUTPUT_LOAD='(1.0,-1.0)';
    'PL7C':
      PIN_NUMBER='(H4,0,0,0,0,0,0)';
      BIDIRECTIONAL='TRUE';
      INPUT_LOAD='(-0.01,0.01)';
      OUTPUT_LOAD='(1.0,-1.0)';
    'PL7D':
      PIN_NUMBER='(H3,0,0,0,0,0,0)';
      BIDIRECTIONAL='TRUE';
      INPUT_LOAD='(-0.01,0.01)';
      OUTPUT_LOAD='(1.0,-1.0)';
    'PL10A':
      PIN_NUMBER='(H2,0,0,0,0,0,0)';
      BIDIRECTIONAL='TRUE';
      INPUT_LOAD='(-0.01,0.01)';
      OUTPUT_LOAD='(1.0,-1.0)';
    'PL10B':
      PIN_NUMBER='(H1,0,0,0,0,0,0)';
      BIDIRECTIONAL='TRUE';
      INPUT_LOAD='(-0.01,0.01)';
      OUTPUT_LOAD='(1.0,-1.0)';
    'PL10C':
      PIN_NUMBER='(J7,0,0,0,0,0,0)';
      BIDIRECTIONAL='TRUE';
      INPUT_LOAD='(-0.01,0.01)';
      OUTPUT_LOAD='(1.0,-1.0)';
    'PL10D':
      PIN_NUMBER='(J6,0,0,0,0,0,0)';
      BIDIRECTIONAL='TRUE';
      INPUT_LOAD='(-0.01,0.01)';
      OUTPUT_LOAD='(1.0,-1.0)';
    'PL11A':
      PIN_NUMBER='(H5,0,0,0,0,0,0)';
      BIDIRECTIONAL='TRUE';
      INPUT_LOAD='(-0.01,0.01)';
      OUTPUT_LOAD='(1.0,-1.0)';
    'PL11B':
      PIN_NUMBER='(J5,0,0,0,0,0,0)';
      BIDIRECTIONAL='TRUE';
      INPUT_LOAD='(-0.01,0.01)';
      OUTPUT_LOAD='(1.0,-1.0)';
    'PL11C':
      PIN_NUMBER='(J4,0,0,0,0,0,0)';
      BIDIRECTIONAL='TRUE';
      INPUT_LOAD='(-0.01,0.01)';
      OUTPUT_LOAD='(1.0,-1.0)';
    'PL11D':
      PIN_NUMBER='(J3,0,0,0,0,0,0)';
      BIDIRECTIONAL='TRUE';
      INPUT_LOAD='(-0.01,0.01)';
      OUTPUT_LOAD='(1.0,-1.0)';
    'PL12A':
      PIN_NUMBER='(J2,0,0,0,0,0,0)';
      BIDIRECTIONAL='TRUE';
      INPUT_LOAD='(-0.01,0.01)';
      OUTPUT_LOAD='(1.0,-1.0)';
    'PL12B':
      PIN_NUMBER='(J1,0,0,0,0,0,0)';
      BIDIRECTIONAL='TRUE';
      INPUT_LOAD='(-0.01,0.01)';
      OUTPUT_LOAD='(1.0,-1.0)';
    'PL12C':
      PIN_NUMBER='(K7,0,0,0,0,0,0)';
      BIDIRECTIONAL='TRUE';
      INPUT_LOAD='(-0.01,0.01)';
      OUTPUT_LOAD='(1.0,-1.0)';
    'PL12D':
      PIN_NUMBER='(K6,0,0,0,0,0,0)';
      BIDIRECTIONAL='TRUE';
      INPUT_LOAD='(-0.01,0.01)';
      OUTPUT_LOAD='(1.0,-1.0)';
    'PB5A':
      PIN_NUMBER='(0,AA2,0,0,0,0,0)';
      BIDIRECTIONAL='TRUE';
      INPUT_LOAD='(-0.01,0.01)';
      OUTPUT_LOAD='(1.0,-1.0)';
    'PB5B':
      PIN_NUMBER='(0,AB2,0,0,0,0,0)';
      BIDIRECTIONAL='TRUE';
      INPUT_LOAD='(-0.01,0.01)';
      OUTPUT_LOAD='(1.0,-1.0)';
    'PB5C':
      PIN_NUMBER='(0,V6,0,0,0,0,0)';
      BIDIRECTIONAL='TRUE';
      INPUT_LOAD='(-0.01,0.01)';
      OUTPUT_LOAD='(1.0,-1.0)';
    'PB5D':
      PIN_NUMBER='(0,U6,0,0,0,0,0)';
      BIDIRECTIONAL='TRUE';
      INPUT_LOAD='(-0.01,0.01)';
      OUTPUT_LOAD='(1.0,-1.0)';
    'PB7A||CSSPIN':
      PIN_NUMBER='(0,AA3,0,0,0,0,0)';
      BIDIRECTIONAL='TRUE';
      INPUT_LOAD='(-0.01,0.01)';
      OUTPUT_LOAD='(1.0,-1.0)';
    'PB7B':
      PIN_NUMBER='(0,AB3,0,0,0,0,0)';
      BIDIRECTIONAL='TRUE';
      INPUT_LOAD='(-0.01,0.01)';
      OUTPUT_LOAD='(1.0,-1.0)';
    'PB7C':
      PIN_NUMBER='(0,Y4,0,0,0,0,0)';
      BIDIRECTIONAL='TRUE';
      INPUT_LOAD='(-0.01,0.01)';
      OUTPUT_LOAD='(1.0,-1.0)';
    'PB7D':
      PIN_NUMBER='(0,W5,0,0,0,0,0)';
      BIDIRECTIONAL='TRUE';
      INPUT_LOAD='(-0.01,0.01)';
      OUTPUT_LOAD='(1.0,-1.0)';
    'PB8C':
      PIN_NUMBER='(0,U7,0,0,0,0,0)';
      BIDIRECTIONAL='TRUE';
      INPUT_LOAD='(-0.01,0.01)';
      OUTPUT_LOAD='(1.0,-1.0)';
    'PB8D':
      PIN_NUMBER='(0,T8,0,0,0,0,0)';
      BIDIRECTIONAL='TRUE';
      INPUT_LOAD='(-0.01,0.01)';
      OUTPUT_LOAD='(1.0,-1.0)';
    'PB8A':
      PIN_NUMBER='(0,AA4,0,0,0,0,0)';
      BIDIRECTIONAL='TRUE';
      INPUT_LOAD='(-0.01,0.01)';
      OUTPUT_LOAD='(1.0,-1.0)';
    'PB8B':
      PIN_NUMBER='(0,AB4,0,0,0,0,0)';
      BIDIRECTIONAL='TRUE';
      INPUT_LOAD='(-0.01,0.01)';
      OUTPUT_LOAD='(1.0,-1.0)';
    'PB10A':
      PIN_NUMBER='(0,AA5,0,0,0,0,0)';
      BIDIRECTIONAL='TRUE';
      INPUT_LOAD='(-0.01,0.01)';
      OUTPUT_LOAD='(1.0,-1.0)';
    'PB10B':
      PIN_NUMBER='(0,AB5,0,0,0,0,0)';
      BIDIRECTIONAL='TRUE';
      INPUT_LOAD='(-0.01,0.01)';
      OUTPUT_LOAD='(1.0,-1.0)';
    'PB10C':
      PIN_NUMBER='(0,Y5,0,0,0,0,0)';
      BIDIRECTIONAL='TRUE';
      INPUT_LOAD='(-0.01,0.01)';
      OUTPUT_LOAD='(1.0,-1.0)';
    'PB10D':
      PIN_NUMBER='(0,Y6,0,0,0,0,0)';
      BIDIRECTIONAL='TRUE';
      INPUT_LOAD='(-0.01,0.01)';
      OUTPUT_LOAD='(1.0,-1.0)';
    'PB13C':
      PIN_NUMBER='(0,V8,0,0,0,0,0)';
      BIDIRECTIONAL='TRUE';
      INPUT_LOAD='(-0.01,0.01)';
      OUTPUT_LOAD='(1.0,-1.0)';
    'PB13D':
      PIN_NUMBER='(0,U8,0,0,0,0,0)';
      BIDIRECTIONAL='TRUE';
      INPUT_LOAD='(-0.01,0.01)';
      OUTPUT_LOAD='(1.0,-1.0)';
    'PB16A||MCLK||CCLK':
      PIN_NUMBER='(0,T9,0,0,0,0,0)';
      BIDIRECTIONAL='TRUE';
      INPUT_LOAD='(-0.01,0.01)';
      OUTPUT_LOAD='(1.0,-1.0)';
    'PB16B||SO||SPISO':
      PIN_NUMBER='(0,U9,0,0,0,0,0)';
      BIDIRECTIONAL='TRUE';
      INPUT_LOAD='(-0.01,0.01)';
      OUTPUT_LOAD='(1.0,-1.0)';
    'PB18A':
      PIN_NUMBER='(0,AA8,0,0,0,0,0)';
      BIDIRECTIONAL='TRUE';
      INPUT_LOAD='(-0.01,0.01)';
      OUTPUT_LOAD='(1.0,-1.0)';
    'PB18B':
      PIN_NUMBER='(0,AB8,0,0,0,0,0)';
      BIDIRECTIONAL='TRUE';
      INPUT_LOAD='(-0.01,0.01)';
      OUTPUT_LOAD='(1.0,-1.0)';
    'PB21A':
      PIN_NUMBER='(0,V10,0,0,0,0,0)';
      BIDIRECTIONAL='TRUE';
      INPUT_LOAD='(-0.01,0.01)';
      OUTPUT_LOAD='(1.0,-1.0)';
    'PB21B':
      PIN_NUMBER='(0,W10,0,0,0,0,0)';
      BIDIRECTIONAL='TRUE';
      INPUT_LOAD='(-0.01,0.01)';
      OUTPUT_LOAD='(1.0,-1.0)';
    'PB22A||PCLKT2_0':
      PIN_NUMBER='(0,AA10,0,0,0,0,0)';
      BIDIRECTIONAL='TRUE';
      INPUT_LOAD='(-0.01,0.01)';
      OUTPUT_LOAD='(1.0,-1.0)';
    'PB22B||PCLKC2_0':
      PIN_NUMBER='(0,AB10,0,0,0,0,0)';
      BIDIRECTIONAL='TRUE';
      INPUT_LOAD='(-0.01,0.01)';
      OUTPUT_LOAD='(1.0,-1.0)';
    'PB24A':
      PIN_NUMBER='(0,AA11,0,0,0,0,0)';
      BIDIRECTIONAL='TRUE';
      INPUT_LOAD='(-0.01,0.01)';
      OUTPUT_LOAD='(1.0,-1.0)';
    'PB24B':
      PIN_NUMBER='(0,AB11,0,0,0,0,0)';
      BIDIRECTIONAL='TRUE';
      INPUT_LOAD='(-0.01,0.01)';
      OUTPUT_LOAD='(1.0,-1.0)';
    'PB24C':
      PIN_NUMBER='(0,V11,0,0,0,0,0)';
      BIDIRECTIONAL='TRUE';
      INPUT_LOAD='(-0.01,0.01)';
      OUTPUT_LOAD='(1.0,-1.0)';
    'PB24D':
      PIN_NUMBER='(0,Y11,0,0,0,0,0)';
      BIDIRECTIONAL='TRUE';
      INPUT_LOAD='(-0.01,0.01)';
      OUTPUT_LOAD='(1.0,-1.0)';
    'PB29A||PCLKT2_1':
      PIN_NUMBER='(0,AB12,0,0,0,0,0)';
      BIDIRECTIONAL='TRUE';
      INPUT_LOAD='(-0.01,0.01)';
      OUTPUT_LOAD='(1.0,-1.0)';
    'PB29B||PCLKC2_1':
      PIN_NUMBER='(0,AA12,0,0,0,0,0)';
      BIDIRECTIONAL='TRUE';
      INPUT_LOAD='(-0.01,0.01)';
      OUTPUT_LOAD='(1.0,-1.0)';
    'PB30A':
      PIN_NUMBER='(0,AB13,0,0,0,0,0)';
      BIDIRECTIONAL='TRUE';
      INPUT_LOAD='(-0.01,0.01)';
      OUTPUT_LOAD='(1.0,-1.0)';
    'PB30B':
      PIN_NUMBER='(0,AA13,0,0,0,0,0)';
      BIDIRECTIONAL='TRUE';
      INPUT_LOAD='(-0.01,0.01)';
      OUTPUT_LOAD='(1.0,-1.0)';
    'PB33A':
      PIN_NUMBER='(0,AB14,0,0,0,0,0)';
      BIDIRECTIONAL='TRUE';
      INPUT_LOAD='(-0.01,0.01)';
      OUTPUT_LOAD='(1.0,-1.0)';
    'PB33B':
      PIN_NUMBER='(0,AA14,0,0,0,0,0)';
      BIDIRECTIONAL='TRUE';
      INPUT_LOAD='(-0.01,0.01)';
      OUTPUT_LOAD='(1.0,-1.0)';
    'PB43A':
      PIN_NUMBER='(0,AB19,0,0,0,0,0)';
      BIDIRECTIONAL='TRUE';
      INPUT_LOAD='(-0.01,0.01)';
      OUTPUT_LOAD='(1.0,-1.0)';
    'PB43B':
      PIN_NUMBER='(0,AA19,0,0,0,0,0)';
      BIDIRECTIONAL='TRUE';
      INPUT_LOAD='(-0.01,0.01)';
      OUTPUT_LOAD='(1.0,-1.0)';
    'PB44A':
      PIN_NUMBER='(0,AB20,0,0,0,0,0)';
      BIDIRECTIONAL='TRUE';
      INPUT_LOAD='(-0.01,0.01)';
      OUTPUT_LOAD='(1.0,-1.0)';
    'PB44B':
      PIN_NUMBER='(0,AA20,0,0,0,0,0)';
      BIDIRECTIONAL='TRUE';
      INPUT_LOAD='(-0.01,0.01)';
      OUTPUT_LOAD='(1.0,-1.0)';
    'PB46A||SN':
      PIN_NUMBER='(0,AB21,0,0,0,0,0)';
      BIDIRECTIONAL='TRUE';
      INPUT_LOAD='(-0.01,0.01)';
      OUTPUT_LOAD='(1.0,-1.0)';
    'PB46B||SI||SISPI':
      PIN_NUMBER='(0,AA21,0,0,0,0,0)';
      BIDIRECTIONAL='TRUE';
      INPUT_LOAD='(-0.01,0.01)';
      OUTPUT_LOAD='(1.0,-1.0)';
    'PB35A':
      PIN_NUMBER='(0,AB15,0,0,0,0,0)';
      BIDIRECTIONAL='TRUE';
      INPUT_LOAD='(-0.01,0.01)';
      OUTPUT_LOAD='(1.0,-1.0)';
    'PB35B':
      PIN_NUMBER='(0,AA15,0,0,0,0,0)';
      BIDIRECTIONAL='TRUE';
      INPUT_LOAD='(-0.01,0.01)';
      OUTPUT_LOAD='(1.0,-1.0)';
    'PB11A':
      PIN_NUMBER='(0,AA6,0,0,0,0,0)';
      BIDIRECTIONAL='TRUE';
      INPUT_LOAD='(-0.01,0.01)';
      OUTPUT_LOAD='(1.0,-1.0)';
    'PB11B':
      PIN_NUMBER='(0,AB6,0,0,0,0,0)';
      BIDIRECTIONAL='TRUE';
      INPUT_LOAD='(-0.01,0.01)';
      OUTPUT_LOAD='(1.0,-1.0)';
    'PB11C':
      PIN_NUMBER='(0,W6,0,0,0,0,0)';
      BIDIRECTIONAL='TRUE';
      INPUT_LOAD='(-0.01,0.01)';
      OUTPUT_LOAD='(1.0,-1.0)';
    'PB11D':
      PIN_NUMBER='(0,V7,0,0,0,0,0)';
      BIDIRECTIONAL='TRUE';
      INPUT_LOAD='(-0.01,0.01)';
      OUTPUT_LOAD='(1.0,-1.0)';
    'PB13A':
      PIN_NUMBER='(0,AA7,0,0,0,0,0)';
      BIDIRECTIONAL='TRUE';
      INPUT_LOAD='(-0.01,0.01)';
      OUTPUT_LOAD='(1.0,-1.0)';
    'PB13B':
      PIN_NUMBER='(0,AB7,0,0,0,0,0)';
      BIDIRECTIONAL='TRUE';
      INPUT_LOAD='(-0.01,0.01)';
      OUTPUT_LOAD='(1.0,-1.0)';
    'PB16C':
      PIN_NUMBER='(0,V9,0,0,0,0,0)';
      BIDIRECTIONAL='TRUE';
      INPUT_LOAD='(-0.01,0.01)';
      OUTPUT_LOAD='(1.0,-1.0)';
    'PB16D':
      PIN_NUMBER='(0,W8,0,0,0,0,0)';
      BIDIRECTIONAL='TRUE';
      INPUT_LOAD='(-0.01,0.01)';
      OUTPUT_LOAD='(1.0,-1.0)';
    'PB18C':
      PIN_NUMBER='(0,Y8,0,0,0,0,0)';
      BIDIRECTIONAL='TRUE';
      INPUT_LOAD='(-0.01,0.01)';
      OUTPUT_LOAD='(1.0,-1.0)';
    'PB18D':
      PIN_NUMBER='(0,W9,0,0,0,0,0)';
      BIDIRECTIONAL='TRUE';
      INPUT_LOAD='(-0.01,0.01)';
      OUTPUT_LOAD='(1.0,-1.0)';
    'PB19A':
      PIN_NUMBER='(0,AA9,0,0,0,0,0)';
      BIDIRECTIONAL='TRUE';
      INPUT_LOAD='(-0.01,0.01)';
      OUTPUT_LOAD='(1.0,-1.0)';
    'PB19B':
      PIN_NUMBER='(0,AB9,0,0,0,0,0)';
      BIDIRECTIONAL='TRUE';
      INPUT_LOAD='(-0.01,0.01)';
      OUTPUT_LOAD='(1.0,-1.0)';
    'PB19C':
      PIN_NUMBER='(0,T10,0,0,0,0,0)';
      BIDIRECTIONAL='TRUE';
      INPUT_LOAD='(-0.01,0.01)';
      OUTPUT_LOAD='(1.0,-1.0)';
    'PB19D':
      PIN_NUMBER='(0,U10,0,0,0,0,0)';
      BIDIRECTIONAL='TRUE';
      INPUT_LOAD='(-0.01,0.01)';
      OUTPUT_LOAD='(1.0,-1.0)';
    'PB22C':
      PIN_NUMBER='(0,T11,0,0,0,0,0)';
      BIDIRECTIONAL='TRUE';
      INPUT_LOAD='(-0.01,0.01)';
      OUTPUT_LOAD='(1.0,-1.0)';
    'PB22D':
      PIN_NUMBER='(0,U11,0,0,0,0,0)';
      BIDIRECTIONAL='TRUE';
      INPUT_LOAD='(-0.01,0.01)';
      OUTPUT_LOAD='(1.0,-1.0)';
    'PB27A':
      PIN_NUMBER='(0,Y12,0,0,0,0,0)';
      BIDIRECTIONAL='TRUE';
      INPUT_LOAD='(-0.01,0.01)';
      OUTPUT_LOAD='(1.0,-1.0)';
    'PB27B':
      PIN_NUMBER='(0,T12,0,0,0,0,0)';
      BIDIRECTIONAL='TRUE';
      INPUT_LOAD='(-0.01,0.01)';
      OUTPUT_LOAD='(1.0,-1.0)';
    'PB27C':
      PIN_NUMBER='(0,U12,0,0,0,0,0)';
      BIDIRECTIONAL='TRUE';
      INPUT_LOAD='(-0.01,0.01)';
      OUTPUT_LOAD='(1.0,-1.0)';
    'PB27D':
      PIN_NUMBER='(0,V12,0,0,0,0,0)';
      BIDIRECTIONAL='TRUE';
      INPUT_LOAD='(-0.01,0.01)';
      OUTPUT_LOAD='(1.0,-1.0)';
    'PB29C':
      PIN_NUMBER='(0,V13,0,0,0,0,0)';
      BIDIRECTIONAL='TRUE';
      INPUT_LOAD='(-0.01,0.01)';
      OUTPUT_LOAD='(1.0,-1.0)';
    'PB29D':
      PIN_NUMBER='(0,U13,0,0,0,0,0)';
      BIDIRECTIONAL='TRUE';
      INPUT_LOAD='(-0.01,0.01)';
      OUTPUT_LOAD='(1.0,-1.0)';
    'PB30C':
      PIN_NUMBER='(0,Y13,0,0,0,0,0)';
      BIDIRECTIONAL='TRUE';
      INPUT_LOAD='(-0.01,0.01)';
      OUTPUT_LOAD='(1.0,-1.0)';
    'PB30D':
      PIN_NUMBER='(0,W13,0,0,0,0,0)';
      BIDIRECTIONAL='TRUE';
      INPUT_LOAD='(-0.01,0.01)';
      OUTPUT_LOAD='(1.0,-1.0)';
    'PB33C':
      PIN_NUMBER='(0,Y14,0,0,0,0,0)';
      BIDIRECTIONAL='TRUE';
      INPUT_LOAD='(-0.01,0.01)';
      OUTPUT_LOAD='(1.0,-1.0)';
    'PB33D':
      PIN_NUMBER='(0,W14,0,0,0,0,0)';
      BIDIRECTIONAL='TRUE';
      INPUT_LOAD='(-0.01,0.01)';
      OUTPUT_LOAD='(1.0,-1.0)';
    'PB32A':
      PIN_NUMBER='(0,T13,0,0,0,0,0)';
      BIDIRECTIONAL='TRUE';
      INPUT_LOAD='(-0.01,0.01)';
      OUTPUT_LOAD='(1.0,-1.0)';
    'PB32B':
      PIN_NUMBER='(0,T14,0,0,0,0,0)';
      BIDIRECTIONAL='TRUE';
      INPUT_LOAD='(-0.01,0.01)';
      OUTPUT_LOAD='(1.0,-1.0)';
    'PB32C':
      PIN_NUMBER='(0,U14,0,0,0,0,0)';
      BIDIRECTIONAL='TRUE';
      INPUT_LOAD='(-0.01,0.01)';
      OUTPUT_LOAD='(1.0,-1.0)';
    'PB32D':
      PIN_NUMBER='(0,V14,0,0,0,0,0)';
      BIDIRECTIONAL='TRUE';
      INPUT_LOAD='(-0.01,0.01)';
      OUTPUT_LOAD='(1.0,-1.0)';
    'PB35C':
      PIN_NUMBER='(0,Y15,0,0,0,0,0)';
      BIDIRECTIONAL='TRUE';
      INPUT_LOAD='(-0.01,0.01)';
      OUTPUT_LOAD='(1.0,-1.0)';
    'PB35D':
      PIN_NUMBER='(0,W15,0,0,0,0,0)';
      BIDIRECTIONAL='TRUE';
      INPUT_LOAD='(-0.01,0.01)';
      OUTPUT_LOAD='(1.0,-1.0)';
    'PB38A':
      PIN_NUMBER='(0,AB16,0,0,0,0,0)';
      BIDIRECTIONAL='TRUE';
      INPUT_LOAD='(-0.01,0.01)';
      OUTPUT_LOAD='(1.0,-1.0)';
    'PB38B':
      PIN_NUMBER='(0,AA16,0,0,0,0,0)';
      BIDIRECTIONAL='TRUE';
      INPUT_LOAD='(-0.01,0.01)';
      OUTPUT_LOAD='(1.0,-1.0)';
    'PB38C':
      PIN_NUMBER='(0,V15,0,0,0,0,0)';
      BIDIRECTIONAL='TRUE';
      INPUT_LOAD='(-0.01,0.01)';
      OUTPUT_LOAD='(1.0,-1.0)';
    'PB38D':
      PIN_NUMBER='(0,U15,0,0,0,0,0)';
      BIDIRECTIONAL='TRUE';
      INPUT_LOAD='(-0.01,0.01)';
      OUTPUT_LOAD='(1.0,-1.0)';
    'PB40A':
      PIN_NUMBER='(0,AB17,0,0,0,0,0)';
      BIDIRECTIONAL='TRUE';
      INPUT_LOAD='(-0.01,0.01)';
      OUTPUT_LOAD='(1.0,-1.0)';
    'PB40B':
      PIN_NUMBER='(0,AA17,0,0,0,0,0)';
      BIDIRECTIONAL='TRUE';
      INPUT_LOAD='(-0.01,0.01)';
      OUTPUT_LOAD='(1.0,-1.0)';
    'PB40C':
      PIN_NUMBER='(0,Y17,0,0,0,0,0)';
      BIDIRECTIONAL='TRUE';
      INPUT_LOAD='(-0.01,0.01)';
      OUTPUT_LOAD='(1.0,-1.0)';
    'PB40D':
      PIN_NUMBER='(0,V16,0,0,0,0,0)';
      BIDIRECTIONAL='TRUE';
      INPUT_LOAD='(-0.01,0.01)';
      OUTPUT_LOAD='(1.0,-1.0)';
    'PB41A':
      PIN_NUMBER='(0,AB18,0,0,0,0,0)';
      BIDIRECTIONAL='TRUE';
      INPUT_LOAD='(-0.01,0.01)';
      OUTPUT_LOAD='(1.0,-1.0)';
    'PB41B':
      PIN_NUMBER='(0,AA18,0,0,0,0,0)';
      BIDIRECTIONAL='TRUE';
      INPUT_LOAD='(-0.01,0.01)';
      OUTPUT_LOAD='(1.0,-1.0)';
    'PB41C':
      PIN_NUMBER='(0,Y18,0,0,0,0,0)';
      BIDIRECTIONAL='TRUE';
      INPUT_LOAD='(-0.01,0.01)';
      OUTPUT_LOAD='(1.0,-1.0)';
    'PB41D':
      PIN_NUMBER='(0,W17,0,0,0,0,0)';
      BIDIRECTIONAL='TRUE';
      INPUT_LOAD='(-0.01,0.01)';
      OUTPUT_LOAD='(1.0,-1.0)';
    'PB43C':
      PIN_NUMBER='(0,T15,0,0,0,0,0)';
      BIDIRECTIONAL='TRUE';
      INPUT_LOAD='(-0.01,0.01)';
      OUTPUT_LOAD='(1.0,-1.0)';
    'PB43D':
      PIN_NUMBER='(0,U16,0,0,0,0,0)';
      BIDIRECTIONAL='TRUE';
      INPUT_LOAD='(-0.01,0.01)';
      OUTPUT_LOAD='(1.0,-1.0)';
    'PB44C':
      PIN_NUMBER='(0,Y19,0,0,0,0,0)';
      BIDIRECTIONAL='TRUE';
      INPUT_LOAD='(-0.01,0.01)';
      OUTPUT_LOAD='(1.0,-1.0)';
    'PB44D':
      PIN_NUMBER='(0,W18,0,0,0,0,0)';
      BIDIRECTIONAL='TRUE';
      INPUT_LOAD='(-0.01,0.01)';
      OUTPUT_LOAD='(1.0,-1.0)';
    'PB46C':
      PIN_NUMBER='(0,V17,0,0,0,0,0)';
      BIDIRECTIONAL='TRUE';
      INPUT_LOAD='(-0.01,0.01)';
      OUTPUT_LOAD='(1.0,-1.0)';
    'PB46D':
      PIN_NUMBER='(0,T16,0,0,0,0,0)';
      BIDIRECTIONAL='TRUE';
      INPUT_LOAD='(-0.01,0.01)';
      OUTPUT_LOAD='(1.0,-1.0)';
    'PB21C':
      PIN_NUMBER='(0,Y9,0,0,0,0,0)';
      BIDIRECTIONAL='TRUE';
      INPUT_LOAD='(-0.01,0.01)';
      OUTPUT_LOAD='(1.0,-1.0)';
    'PB21D':
      PIN_NUMBER='(0,Y10,0,0,0,0,0)';
      BIDIRECTIONAL='TRUE';
      INPUT_LOAD='(-0.01,0.01)';
      OUTPUT_LOAD='(1.0,-1.0)';
    'PT43B||R_GPLLC':
      PIN_NUMBER='(0,0,B21,0,0,0,0)';
      BIDIRECTIONAL='TRUE';
      INPUT_LOAD='(-0.01,0.01)';
      OUTPUT_LOAD='(1.0,-1.0)';
    'PT43A||R_GPLLT':
      PIN_NUMBER='(0,0,A20,0,0,0,0)';
      BIDIRECTIONAL='TRUE';
      INPUT_LOAD='(-0.01,0.01)';
      OUTPUT_LOAD='(1.0,-1.0)';
    'PT41B':
      PIN_NUMBER='(0,0,B19,0,0,0,0)';
      BIDIRECTIONAL='TRUE';
      INPUT_LOAD='(-0.01,0.01)';
      OUTPUT_LOAD='(1.0,-1.0)';
    'PT41A':
      PIN_NUMBER='(0,0,A18,0,0,0,0)';
      BIDIRECTIONAL='TRUE';
      INPUT_LOAD='(-0.01,0.01)';
      OUTPUT_LOAD='(1.0,-1.0)';
    'PT31B':
      PIN_NUMBER='(0,0,F14,0,0,0,0)';
      BIDIRECTIONAL='TRUE';
      INPUT_LOAD='(-0.01,0.01)';
      OUTPUT_LOAD='(1.0,-1.0)';
    'PT31A':
      PIN_NUMBER='(0,0,G14,0,0,0,0)';
      BIDIRECTIONAL='TRUE';
      INPUT_LOAD='(-0.01,0.01)';
      OUTPUT_LOAD='(1.0,-1.0)';
    'PT28B':
      PIN_NUMBER='(0,0,F12,0,0,0,0)';
      BIDIRECTIONAL='TRUE';
      INPUT_LOAD='(-0.01,0.01)';
      OUTPUT_LOAD='(1.0,-1.0)';
    'PT28A':
      PIN_NUMBER='(0,0,G12,0,0,0,0)';
      BIDIRECTIONAL='TRUE';
      INPUT_LOAD='(-0.01,0.01)';
      OUTPUT_LOAD='(1.0,-1.0)';
    'PT27D||SDA||PCLKC0_0':
      PIN_NUMBER='(0,0,A12,0,0,0,0)';
      BIDIRECTIONAL='TRUE';
      INPUT_LOAD='(-0.01,0.01)';
      OUTPUT_LOAD='(1.0,-1.0)';
    'PT27C||SCL||PCLKT0_0':
      PIN_NUMBER='(0,0,B12,0,0,0,0)';
      BIDIRECTIONAL='TRUE';
      INPUT_LOAD='(-0.01,0.01)';
      OUTPUT_LOAD='(1.0,-1.0)';
    'PT44B||R_GPLLC':
      PIN_NUMBER='(0,0,B22,0,0,0,0)';
      BIDIRECTIONAL='TRUE';
      INPUT_LOAD='(-0.01,0.01)';
      OUTPUT_LOAD='(1.0,-1.0)';
    'PT44A||R_GPLLT':
      PIN_NUMBER='(0,0,A21,0,0,0,0)';
      BIDIRECTIONAL='TRUE';
      INPUT_LOAD='(-0.01,0.01)';
      OUTPUT_LOAD='(1.0,-1.0)';
    'PT23B||PCLKC0_1':
      PIN_NUMBER='(0,0,A10,0,0,0,0)';
      BIDIRECTIONAL='TRUE';
      INPUT_LOAD='(-0.01,0.01)';
      OUTPUT_LOAD='(1.0,-1.0)';
    'PT23A||PCLKT0_1':
      PIN_NUMBER='(0,0,B10,0,0,0,0)';
      BIDIRECTIONAL='TRUE';
      INPUT_LOAD='(-0.01,0.01)';
      OUTPUT_LOAD='(1.0,-1.0)';
    'PT15B':
      PIN_NUMBER='(0,0,D8,0,0,0,0)';
      BIDIRECTIONAL='TRUE';
      INPUT_LOAD='(-0.01,0.01)';
      OUTPUT_LOAD='(1.0,-1.0)';
    'PT9D':
      PIN_NUMBER='(0,0,F7,0,0,0,0)';
      BIDIRECTIONAL='TRUE';
      INPUT_LOAD='(-0.01,0.01)';
      OUTPUT_LOAD='(1.0,-1.0)';
    'PT9B||L_GPLLC':
      PIN_NUMBER='(0,0,A2,0,0,0,0)';
      BIDIRECTIONAL='TRUE';
      INPUT_LOAD='(-0.01,0.01)';
      OUTPUT_LOAD='(1.0,-1.0)';
    'PT9C':
      PIN_NUMBER='(0,0,E6,0,0,0,0)';
      BIDIRECTIONAL='TRUE';
      INPUT_LOAD='(-0.01,0.01)';
      OUTPUT_LOAD='(1.0,-1.0)';
    'PT9A||L_GPLLT':
      PIN_NUMBER='(0,0,B1,0,0,0,0)';
      BIDIRECTIONAL='TRUE';
      INPUT_LOAD='(-0.01,0.01)';
      OUTPUT_LOAD='(1.0,-1.0)';
    'PT15A':
      PIN_NUMBER='(0,0,C8,0,0,0,0)';
      BIDIRECTIONAL='TRUE';
      INPUT_LOAD='(-0.01,0.01)';
      OUTPUT_LOAD='(1.0,-1.0)';
    'PT11A':
      PIN_NUMBER='(0,0,B3,0,0,0,0)';
      BIDIRECTIONAL='TRUE';
      INPUT_LOAD='(-0.01,0.01)';
      OUTPUT_LOAD='(1.0,-1.0)';
    'PT11B':
      PIN_NUMBER='(0,0,A4,0,0,0,0)';
      BIDIRECTIONAL='TRUE';
      INPUT_LOAD='(-0.01,0.01)';
      OUTPUT_LOAD='(1.0,-1.0)';
    'PT22A':
      PIN_NUMBER='(0,0,F10,0,0,0,0)';
      BIDIRECTIONAL='TRUE';
      INPUT_LOAD='(-0.01,0.01)';
      OUTPUT_LOAD='(1.0,-1.0)';
    'PT22B':
      PIN_NUMBER='(0,0,E10,0,0,0,0)';
      BIDIRECTIONAL='TRUE';
      INPUT_LOAD='(-0.01,0.01)';
      OUTPUT_LOAD='(1.0,-1.0)';
    'PT11C':
      PIN_NUMBER='(0,0,F8,0,0,0,0)';
      BIDIRECTIONAL='TRUE';
      INPUT_LOAD='(-0.01,0.01)';
      OUTPUT_LOAD='(1.0,-1.0)';
    'PT11D':
      PIN_NUMBER='(0,0,G8,0,0,0,0)';
      BIDIRECTIONAL='TRUE';
      INPUT_LOAD='(-0.01,0.01)';
      OUTPUT_LOAD='(1.0,-1.0)';
    'PT10A':
      PIN_NUMBER='(0,0,B2,0,0,0,0)';
      BIDIRECTIONAL='TRUE';
      INPUT_LOAD='(-0.01,0.01)';
      OUTPUT_LOAD='(1.0,-1.0)';
    'PT10B':
      PIN_NUMBER='(0,0,A3,0,0,0,0)';
      BIDIRECTIONAL='TRUE';
      INPUT_LOAD='(-0.01,0.01)';
      OUTPUT_LOAD='(1.0,-1.0)';
    'PT10C':
      PIN_NUMBER='(0,0,C3,0,0,0,0)';
      BIDIRECTIONAL='TRUE';
      INPUT_LOAD='(-0.01,0.01)';
      OUTPUT_LOAD='(1.0,-1.0)';
    'PT10D':
      PIN_NUMBER='(0,0,C4,0,0,0,0)';
      BIDIRECTIONAL='TRUE';
      INPUT_LOAD='(-0.01,0.01)';
      OUTPUT_LOAD='(1.0,-1.0)';
    'PT12A':
      PIN_NUMBER='(0,0,B4,0,0,0,0)';
      BIDIRECTIONAL='TRUE';
      INPUT_LOAD='(-0.01,0.01)';
      OUTPUT_LOAD='(1.0,-1.0)';
    'PT12B':
      PIN_NUMBER='(0,0,A5,0,0,0,0)';
      BIDIRECTIONAL='TRUE';
      INPUT_LOAD='(-0.01,0.01)';
      OUTPUT_LOAD='(1.0,-1.0)';
    'PT12C':
      PIN_NUMBER='(0,0,D5,0,0,0,0)';
      BIDIRECTIONAL='TRUE';
      INPUT_LOAD='(-0.01,0.01)';
      OUTPUT_LOAD='(1.0,-1.0)';
    'PT12D':
      PIN_NUMBER='(0,0,C5,0,0,0,0)';
      BIDIRECTIONAL='TRUE';
      INPUT_LOAD='(-0.01,0.01)';
      OUTPUT_LOAD='(1.0,-1.0)';
    'PT13A':
      PIN_NUMBER='(0,0,B5,0,0,0,0)';
      BIDIRECTIONAL='TRUE';
      INPUT_LOAD='(-0.01,0.01)';
      OUTPUT_LOAD='(1.0,-1.0)';
    'PT13B':
      PIN_NUMBER='(0,0,A6,0,0,0,0)';
      BIDIRECTIONAL='TRUE';
      INPUT_LOAD='(-0.01,0.01)';
      OUTPUT_LOAD='(1.0,-1.0)';
    'PT13C':
      PIN_NUMBER='(0,0,D6,0,0,0,0)';
      BIDIRECTIONAL='TRUE';
      INPUT_LOAD='(-0.01,0.01)';
      OUTPUT_LOAD='(1.0,-1.0)';
    'PT13D':
      PIN_NUMBER='(0,0,E7,0,0,0,0)';
      BIDIRECTIONAL='TRUE';
      INPUT_LOAD='(-0.01,0.01)';
      OUTPUT_LOAD='(1.0,-1.0)';
    'PT14A':
      PIN_NUMBER='(0,0,B6,0,0,0,0)';
      BIDIRECTIONAL='TRUE';
      INPUT_LOAD='(-0.01,0.01)';
      OUTPUT_LOAD='(1.0,-1.0)';
    'PT14B':
      PIN_NUMBER='(0,0,A7,0,0,0,0)';
      BIDIRECTIONAL='TRUE';
      INPUT_LOAD='(-0.01,0.01)';
      OUTPUT_LOAD='(1.0,-1.0)';
    'PT14C':
      PIN_NUMBER='(0,0,C6,0,0,0,0)';
      BIDIRECTIONAL='TRUE';
      INPUT_LOAD='(-0.01,0.01)';
      OUTPUT_LOAD='(1.0,-1.0)';
    'PT14D':
      PIN_NUMBER='(0,0,D7,0,0,0,0)';
      BIDIRECTIONAL='TRUE';
      INPUT_LOAD='(-0.01,0.01)';
      OUTPUT_LOAD='(1.0,-1.0)';
    'PT20A':
      PIN_NUMBER='(0,0,B8,0,0,0,0)';
      BIDIRECTIONAL='TRUE';
      INPUT_LOAD='(-0.01,0.01)';
      OUTPUT_LOAD='(1.0,-1.0)';
    'PT20B':
      PIN_NUMBER='(0,0,A8,0,0,0,0)';
      BIDIRECTIONAL='TRUE';
      INPUT_LOAD='(-0.01,0.01)';
      OUTPUT_LOAD='(1.0,-1.0)';
    'PT20C':
      PIN_NUMBER='(0,0,C9,0,0,0,0)';
      BIDIRECTIONAL='TRUE';
      INPUT_LOAD='(-0.01,0.01)';
      OUTPUT_LOAD='(1.0,-1.0)';
    'PT20D':
      PIN_NUMBER='(0,0,D9,0,0,0,0)';
      BIDIRECTIONAL='TRUE';
      INPUT_LOAD='(-0.01,0.01)';
      OUTPUT_LOAD='(1.0,-1.0)';
    'PT21A':
      PIN_NUMBER='(0,0,B9,0,0,0,0)';
      BIDIRECTIONAL='TRUE';
      INPUT_LOAD='(-0.01,0.01)';
      OUTPUT_LOAD='(1.0,-1.0)';
    'PT21B':
      PIN_NUMBER='(0,0,A9,0,0,0,0)';
      BIDIRECTIONAL='TRUE';
      INPUT_LOAD='(-0.01,0.01)';
      OUTPUT_LOAD='(1.0,-1.0)';
    'PT21C':
      PIN_NUMBER='(0,0,F9,0,0,0,0)';
      BIDIRECTIONAL='TRUE';
      INPUT_LOAD='(-0.01,0.01)';
      OUTPUT_LOAD='(1.0,-1.0)';
    'PT21D':
      PIN_NUMBER='(0,0,G9,0,0,0,0)';
      BIDIRECTIONAL='TRUE';
      INPUT_LOAD='(-0.01,0.01)';
      OUTPUT_LOAD='(1.0,-1.0)';
    'PT23C':
      PIN_NUMBER='(0,0,G11,0,0,0,0)';
      BIDIRECTIONAL='TRUE';
      INPUT_LOAD='(-0.01,0.01)';
      OUTPUT_LOAD='(1.0,-1.0)';
    'PT23D':
      PIN_NUMBER='(0,0,F11,0,0,0,0)';
      BIDIRECTIONAL='TRUE';
      INPUT_LOAD='(-0.01,0.01)';
      OUTPUT_LOAD='(1.0,-1.0)';
    'PT24A':
      PIN_NUMBER='(0,0,B11,0,0,0,0)';
      BIDIRECTIONAL='TRUE';
      INPUT_LOAD='(-0.01,0.01)';
      OUTPUT_LOAD='(1.0,-1.0)';
    'PT24B':
      PIN_NUMBER='(0,0,A11,0,0,0,0)';
      BIDIRECTIONAL='TRUE';
      INPUT_LOAD='(-0.01,0.01)';
      OUTPUT_LOAD='(1.0,-1.0)';
    'PT24C':
      PIN_NUMBER='(0,0,E11,0,0,0,0)';
      BIDIRECTIONAL='TRUE';
      INPUT_LOAD='(-0.01,0.01)';
      OUTPUT_LOAD='(1.0,-1.0)';
    'PT24D':
      PIN_NUMBER='(0,0,D11,0,0,0,0)';
      BIDIRECTIONAL='TRUE';
      INPUT_LOAD='(-0.01,0.01)';
      OUTPUT_LOAD='(1.0,-1.0)';
    'PT27A':
      PIN_NUMBER='(0,0,D12,0,0,0,0)';
      BIDIRECTIONAL='TRUE';
      INPUT_LOAD='(-0.01,0.01)';
      OUTPUT_LOAD='(1.0,-1.0)';
    'PT27B':
      PIN_NUMBER='(0,0,E12,0,0,0,0)';
      BIDIRECTIONAL='TRUE';
      INPUT_LOAD='(-0.01,0.01)';
      OUTPUT_LOAD='(1.0,-1.0)';
    'PT28C':
      PIN_NUMBER='(0,0,E13,0,0,0,0)';
      BIDIRECTIONAL='TRUE';
      INPUT_LOAD='(-0.01,0.01)';
      OUTPUT_LOAD='(1.0,-1.0)';
    'PT28D':
      PIN_NUMBER='(0,0,F13,0,0,0,0)';
      BIDIRECTIONAL='TRUE';
      INPUT_LOAD='(-0.01,0.01)';
      OUTPUT_LOAD='(1.0,-1.0)';
    'PT29A':
      PIN_NUMBER='(0,0,A13,0,0,0,0)';
      BIDIRECTIONAL='TRUE';
      INPUT_LOAD='(-0.01,0.01)';
      OUTPUT_LOAD='(1.0,-1.0)';
    'PT29B':
      PIN_NUMBER='(0,0,B13,0,0,0,0)';
      BIDIRECTIONAL='TRUE';
      INPUT_LOAD='(-0.01,0.01)';
      OUTPUT_LOAD='(1.0,-1.0)';
    'PT29C':
      PIN_NUMBER='(0,0,C13,0,0,0,0)';
      BIDIRECTIONAL='TRUE';
      INPUT_LOAD='(-0.01,0.01)';
      OUTPUT_LOAD='(1.0,-1.0)';
    'PT29D':
      PIN_NUMBER='(0,0,D13,0,0,0,0)';
      BIDIRECTIONAL='TRUE';
      INPUT_LOAD='(-0.01,0.01)';
      OUTPUT_LOAD='(1.0,-1.0)';
    'PT30A':
      PIN_NUMBER='(0,0,A14,0,0,0,0)';
      BIDIRECTIONAL='TRUE';
      INPUT_LOAD='(-0.01,0.01)';
      OUTPUT_LOAD='(1.0,-1.0)';
    'PT30B':
      PIN_NUMBER='(0,0,B14,0,0,0,0)';
      BIDIRECTIONAL='TRUE';
      INPUT_LOAD='(-0.01,0.01)';
      OUTPUT_LOAD='(1.0,-1.0)';
    'PT30C':
      PIN_NUMBER='(0,0,C14,0,0,0,0)';
      BIDIRECTIONAL='TRUE';
      INPUT_LOAD='(-0.01,0.01)';
      OUTPUT_LOAD='(1.0,-1.0)';
    'PT30D':
      PIN_NUMBER='(0,0,D14,0,0,0,0)';
      BIDIRECTIONAL='TRUE';
      INPUT_LOAD='(-0.01,0.01)';
      OUTPUT_LOAD='(1.0,-1.0)';
    'PT38A':
      PIN_NUMBER='(0,0,A15,0,0,0,0)';
      BIDIRECTIONAL='TRUE';
      INPUT_LOAD='(-0.01,0.01)';
      OUTPUT_LOAD='(1.0,-1.0)';
    'PT38B':
      PIN_NUMBER='(0,0,B15,0,0,0,0)';
      BIDIRECTIONAL='TRUE';
      INPUT_LOAD='(-0.01,0.01)';
      OUTPUT_LOAD='(1.0,-1.0)';
    'PT38C':
      PIN_NUMBER='(0,0,C15,0,0,0,0)';
      BIDIRECTIONAL='TRUE';
      INPUT_LOAD='(-0.01,0.01)';
      OUTPUT_LOAD='(1.0,-1.0)';
    'PT38D':
      PIN_NUMBER='(0,0,D15,0,0,0,0)';
      BIDIRECTIONAL='TRUE';
      INPUT_LOAD='(-0.01,0.01)';
      OUTPUT_LOAD='(1.0,-1.0)';
    'PT39A':
      PIN_NUMBER='(0,0,A16,0,0,0,0)';
      BIDIRECTIONAL='TRUE';
      INPUT_LOAD='(-0.01,0.01)';
      OUTPUT_LOAD='(1.0,-1.0)';
    'PT39B':
      PIN_NUMBER='(0,0,B17,0,0,0,0)';
      BIDIRECTIONAL='TRUE';
      INPUT_LOAD='(-0.01,0.01)';
      OUTPUT_LOAD='(1.0,-1.0)';
    'PT39C':
      PIN_NUMBER='(0,0,C17,0,0,0,0)';
      BIDIRECTIONAL='TRUE';
      INPUT_LOAD='(-0.01,0.01)';
      OUTPUT_LOAD='(1.0,-1.0)';
    'PT39D':
      PIN_NUMBER='(0,0,D16,0,0,0,0)';
      BIDIRECTIONAL='TRUE';
      INPUT_LOAD='(-0.01,0.01)';
      OUTPUT_LOAD='(1.0,-1.0)';
    'PT40A':
      PIN_NUMBER='(0,0,A17,0,0,0,0)';
      BIDIRECTIONAL='TRUE';
      INPUT_LOAD='(-0.01,0.01)';
      OUTPUT_LOAD='(1.0,-1.0)';
    'PT40B':
      PIN_NUMBER='(0,0,B18,0,0,0,0)';
      BIDIRECTIONAL='TRUE';
      INPUT_LOAD='(-0.01,0.01)';
      OUTPUT_LOAD='(1.0,-1.0)';
    'PT40C':
      PIN_NUMBER='(0,0,E16,0,0,0,0)';
      BIDIRECTIONAL='TRUE';
      INPUT_LOAD='(-0.01,0.01)';
      OUTPUT_LOAD='(1.0,-1.0)';
    'PT40D':
      PIN_NUMBER='(0,0,D17,0,0,0,0)';
      BIDIRECTIONAL='TRUE';
      INPUT_LOAD='(-0.01,0.01)';
      OUTPUT_LOAD='(1.0,-1.0)';
    'PT41C':
      PIN_NUMBER='(0,0,C18,0,0,0,0)';
      BIDIRECTIONAL='TRUE';
      INPUT_LOAD='(-0.01,0.01)';
      OUTPUT_LOAD='(1.0,-1.0)';
    'PT41D':
      PIN_NUMBER='(0,0,D18,0,0,0,0)';
      BIDIRECTIONAL='TRUE';
      INPUT_LOAD='(-0.01,0.01)';
      OUTPUT_LOAD='(1.0,-1.0)';
    'PT42A':
      PIN_NUMBER='(0,0,A19,0,0,0,0)';
      BIDIRECTIONAL='TRUE';
      INPUT_LOAD='(-0.01,0.01)';
      OUTPUT_LOAD='(1.0,-1.0)';
    'PT42B':
      PIN_NUMBER='(0,0,B20,0,0,0,0)';
      BIDIRECTIONAL='TRUE';
      INPUT_LOAD='(-0.01,0.01)';
      OUTPUT_LOAD='(1.0,-1.0)';
    'PT42C':
      PIN_NUMBER='(0,0,F15,0,0,0,0)';
      BIDIRECTIONAL='TRUE';
      INPUT_LOAD='(-0.01,0.01)';
      OUTPUT_LOAD='(1.0,-1.0)';
    'PT42D':
      PIN_NUMBER='(0,0,G15,0,0,0,0)';
      BIDIRECTIONAL='TRUE';
      INPUT_LOAD='(-0.01,0.01)';
      OUTPUT_LOAD='(1.0,-1.0)';
    'PT43C':
      PIN_NUMBER='(0,0,C19,0,0,0,0)';
      BIDIRECTIONAL='TRUE';
      INPUT_LOAD='(-0.01,0.01)';
      OUTPUT_LOAD='(1.0,-1.0)';
    'PT43D':
      PIN_NUMBER='(0,0,C20,0,0,0,0)';
      BIDIRECTIONAL='TRUE';
      INPUT_LOAD='(-0.01,0.01)';
      OUTPUT_LOAD='(1.0,-1.0)';
    'PT15C||TDO':
      PIN_NUMBER='(0,0,0,E8,0,0,0)';
      BIDIRECTIONAL='TRUE';
      INPUT_LOAD='(-0.01,0.01)';
      OUTPUT_LOAD='(1.0,-1.0)';
    'PT15D||TDI':
      PIN_NUMBER='(0,0,0,E9,0,0,0)';
      BIDIRECTIONAL='TRUE';
      INPUT_LOAD='(-0.01,0.01)';
      OUTPUT_LOAD='(1.0,-1.0)';
    'PT22C||TCK':
      PIN_NUMBER='(0,0,0,D10,0,0,0)';
      BIDIRECTIONAL='TRUE';
      INPUT_LOAD='(-0.01,0.01)';
      OUTPUT_LOAD='(1.0,-1.0)';
    'PT22D||TMS':
      PIN_NUMBER='(0,0,0,C10,0,0,0)';
      BIDIRECTIONAL='TRUE';
      INPUT_LOAD='(-0.01,0.01)';
      OUTPUT_LOAD='(1.0,-1.0)';
    'PT31D||PROGRAMN':
      PIN_NUMBER='(0,0,0,E15,0,0,0)';
      BIDIRECTIONAL='TRUE';
      INPUT_LOAD='(-0.01,0.01)';
      OUTPUT_LOAD='(1.0,-1.0)';
    'PT44C||INITN':
      PIN_NUMBER='(0,0,0,F16,0,0,0)';
      BIDIRECTIONAL='TRUE';
      INPUT_LOAD='(-0.01,0.01)';
      OUTPUT_LOAD='(1.0,-1.0)';
    'PT44D||DONE':
      PIN_NUMBER='(0,0,0,E17,0,0,0)';
      BIDIRECTIONAL='TRUE';
      INPUT_LOAD='(-0.01,0.01)';
      OUTPUT_LOAD='(1.0,-1.0)';
    'PT31C||JTAGENB':
      PIN_NUMBER='(0,0,0,E14,0,0,0)';
      BIDIRECTIONAL='TRUE';
      INPUT_LOAD='(-0.01,0.01)';
      OUTPUT_LOAD='(1.0,-1.0)';
    'VCC1':
      PIN_NUMBER='(0,0,0,0,K10,0,0)';
      PINUSE='POWER';
      NO_LOAD_CHECK='Both';
      NO_IO_CHECK='Both';
      NO_ASSERT_CHECK='TRUE';
      NO_DIR_CHECK='TRUE';
      ALLOW_CONNECT='TRUE';
    'VCC2':
      PIN_NUMBER='(0,0,0,0,K11,0,0)';
      PINUSE='POWER';
      NO_LOAD_CHECK='Both';
      NO_IO_CHECK='Both';
      NO_ASSERT_CHECK='TRUE';
      NO_DIR_CHECK='TRUE';
      ALLOW_CONNECT='TRUE';
    'VCC3':
      PIN_NUMBER='(0,0,0,0,K12,0,0)';
      PINUSE='POWER';
      NO_LOAD_CHECK='Both';
      NO_IO_CHECK='Both';
      NO_ASSERT_CHECK='TRUE';
      NO_DIR_CHECK='TRUE';
      ALLOW_CONNECT='TRUE';
    'VCC4':
      PIN_NUMBER='(0,0,0,0,K13,0,0)';
      PINUSE='POWER';
      NO_LOAD_CHECK='Both';
      NO_IO_CHECK='Both';
      NO_ASSERT_CHECK='TRUE';
      NO_DIR_CHECK='TRUE';
      ALLOW_CONNECT='TRUE';
    'VCC5':
      PIN_NUMBER='(0,0,0,0,L11,0,0)';
      PINUSE='POWER';
      NO_LOAD_CHECK='Both';
      NO_IO_CHECK='Both';
      NO_ASSERT_CHECK='TRUE';
      NO_DIR_CHECK='TRUE';
      ALLOW_CONNECT='TRUE';
    'VCC6':
      PIN_NUMBER='(0,0,0,0,L12,0,0)';
      PINUSE='POWER';
      NO_LOAD_CHECK='Both';
      NO_IO_CHECK='Both';
      NO_ASSERT_CHECK='TRUE';
      NO_DIR_CHECK='TRUE';
      ALLOW_CONNECT='TRUE';
    'VCC7':
      PIN_NUMBER='(0,0,0,0,M11,0,0)';
      PINUSE='POWER';
      NO_LOAD_CHECK='Both';
      NO_IO_CHECK='Both';
      NO_ASSERT_CHECK='TRUE';
      NO_DIR_CHECK='TRUE';
      ALLOW_CONNECT='TRUE';
    'VCC8':
      PIN_NUMBER='(0,0,0,0,M12,0,0)';
      PINUSE='POWER';
      NO_LOAD_CHECK='Both';
      NO_IO_CHECK='Both';
      NO_ASSERT_CHECK='TRUE';
      NO_DIR_CHECK='TRUE';
      ALLOW_CONNECT='TRUE';
    'VCC9':
      PIN_NUMBER='(0,0,0,0,N10,0,0)';
      PINUSE='POWER';
      NO_LOAD_CHECK='Both';
      NO_IO_CHECK='Both';
      NO_ASSERT_CHECK='TRUE';
      NO_DIR_CHECK='TRUE';
      ALLOW_CONNECT='TRUE';
    'VCC10':
      PIN_NUMBER='(0,0,0,0,N11,0,0)';
      PINUSE='POWER';
      NO_LOAD_CHECK='Both';
      NO_IO_CHECK='Both';
      NO_ASSERT_CHECK='TRUE';
      NO_DIR_CHECK='TRUE';
      ALLOW_CONNECT='TRUE';
    'VCC11':
      PIN_NUMBER='(0,0,0,0,N12,0,0)';
      PINUSE='POWER';
      NO_LOAD_CHECK='Both';
      NO_IO_CHECK='Both';
      NO_ASSERT_CHECK='TRUE';
      NO_DIR_CHECK='TRUE';
      ALLOW_CONNECT='TRUE';
    'VCC12':
      PIN_NUMBER='(0,0,0,0,N13,0,0)';
      PINUSE='POWER';
      NO_LOAD_CHECK='Both';
      NO_IO_CHECK='Both';
      NO_ASSERT_CHECK='TRUE';
      NO_DIR_CHECK='TRUE';
      ALLOW_CONNECT='TRUE';
    'VCCIO5_1':
      PIN_NUMBER='(0,0,0,0,F3,0,0)';
      PINUSE='POWER';
      NO_LOAD_CHECK='Both';
      NO_IO_CHECK='Both';
      NO_ASSERT_CHECK='TRUE';
      NO_DIR_CHECK='TRUE';
      ALLOW_CONNECT='TRUE';
    'VCCIO5_2':
      PIN_NUMBER='(0,0,0,0,J8,0,0)';
      PINUSE='POWER';
      NO_LOAD_CHECK='Both';
      NO_IO_CHECK='Both';
      NO_ASSERT_CHECK='TRUE';
      NO_DIR_CHECK='TRUE';
      ALLOW_CONNECT='TRUE';
    'VCCIO5_3':
      PIN_NUMBER='(0,0,0,0,K8,0,0)';
      PINUSE='POWER';
      NO_LOAD_CHECK='Both';
      NO_IO_CHECK='Both';
      NO_ASSERT_CHECK='TRUE';
      NO_DIR_CHECK='TRUE';
      ALLOW_CONNECT='TRUE';
    'VCCIO4_1':
      PIN_NUMBER='(0,0,0,0,L8,0,0)';
      PINUSE='POWER';
      NO_LOAD_CHECK='Both';
      NO_IO_CHECK='Both';
      NO_ASSERT_CHECK='TRUE';
      NO_DIR_CHECK='TRUE';
      ALLOW_CONNECT='TRUE';
    'VCCIO4_2':
      PIN_NUMBER='(0,0,0,0,M8,0,0)';
      PINUSE='POWER';
      NO_LOAD_CHECK='Both';
      NO_IO_CHECK='Both';
      NO_ASSERT_CHECK='TRUE';
      NO_DIR_CHECK='TRUE';
      ALLOW_CONNECT='TRUE';
    'VCCIO4_3':
      PIN_NUMBER='(0,0,0,0,M3,0,0)';
      PINUSE='POWER';
      NO_LOAD_CHECK='Both';
      NO_IO_CHECK='Both';
      NO_ASSERT_CHECK='TRUE';
      NO_DIR_CHECK='TRUE';
      ALLOW_CONNECT='TRUE';
    'VCCIO3_1':
      PIN_NUMBER='(0,0,0,0,N8,0,0)';
      PINUSE='POWER';
      NO_LOAD_CHECK='Both';
      NO_IO_CHECK='Both';
      NO_ASSERT_CHECK='TRUE';
      NO_DIR_CHECK='TRUE';
      ALLOW_CONNECT='TRUE';
    'VCCIO3_2':
      PIN_NUMBER='(0,0,0,0,P8,0,0)';
      PINUSE='POWER';
      NO_LOAD_CHECK='Both';
      NO_IO_CHECK='Both';
      NO_ASSERT_CHECK='TRUE';
      NO_DIR_CHECK='TRUE';
      ALLOW_CONNECT='TRUE';
    'VCCIO3_3':
      PIN_NUMBER='(0,0,0,0,V3,0,0)';
      PINUSE='POWER';
      NO_LOAD_CHECK='Both';
      NO_IO_CHECK='Both';
      NO_ASSERT_CHECK='TRUE';
      NO_DIR_CHECK='TRUE';
      ALLOW_CONNECT='TRUE';
    'VCCIO2_1':
      PIN_NUMBER='(0,0,0,0,R9,0,0)';
      PINUSE='POWER';
      NO_LOAD_CHECK='Both';
      NO_IO_CHECK='Both';
      NO_ASSERT_CHECK='TRUE';
      NO_DIR_CHECK='TRUE';
      ALLOW_CONNECT='TRUE';
    'VCCIO2_2':
      PIN_NUMBER='(0,0,0,0,R10,0,0)';
      PINUSE='POWER';
      NO_LOAD_CHECK='Both';
      NO_IO_CHECK='Both';
      NO_ASSERT_CHECK='TRUE';
      NO_DIR_CHECK='TRUE';
      ALLOW_CONNECT='TRUE';
    'VCCIO2_3':
      PIN_NUMBER='(0,0,0,0,R11,0,0)';
      PINUSE='POWER';
      NO_LOAD_CHECK='Both';
      NO_IO_CHECK='Both';
      NO_ASSERT_CHECK='TRUE';
      NO_DIR_CHECK='TRUE';
      ALLOW_CONNECT='TRUE';
    'VCCIO2_4':
      PIN_NUMBER='(0,0,0,0,R12,0,0)';
      PINUSE='POWER';
      NO_LOAD_CHECK='Both';
      NO_IO_CHECK='Both';
      NO_ASSERT_CHECK='TRUE';
      NO_DIR_CHECK='TRUE';
      ALLOW_CONNECT='TRUE';
    'VCCIO2_5':
      PIN_NUMBER='(0,0,0,0,R13,0,0)';
      PINUSE='POWER';
      NO_LOAD_CHECK='Both';
      NO_IO_CHECK='Both';
      NO_ASSERT_CHECK='TRUE';
      NO_DIR_CHECK='TRUE';
      ALLOW_CONNECT='TRUE';
    'VCCIO2_6':
      PIN_NUMBER='(0,0,0,0,R14,0,0)';
      PINUSE='POWER';
      NO_LOAD_CHECK='Both';
      NO_IO_CHECK='Both';
      NO_ASSERT_CHECK='TRUE';
      NO_DIR_CHECK='TRUE';
      ALLOW_CONNECT='TRUE';
    'VCCIO2_7':
      PIN_NUMBER='(0,0,0,0,W7,0,0)';
      PINUSE='POWER';
      NO_LOAD_CHECK='Both';
      NO_IO_CHECK='Both';
      NO_ASSERT_CHECK='TRUE';
      NO_DIR_CHECK='TRUE';
      ALLOW_CONNECT='TRUE';
    'VCCIO2_8':
      PIN_NUMBER='(0,0,0,0,W11,0,0)';
      PINUSE='POWER';
      NO_LOAD_CHECK='Both';
      NO_IO_CHECK='Both';
      NO_ASSERT_CHECK='TRUE';
      NO_DIR_CHECK='TRUE';
      ALLOW_CONNECT='TRUE';
    'VCCIO2_9':
      PIN_NUMBER='(0,0,0,0,W16,0,0)';
      PINUSE='POWER';
      NO_LOAD_CHECK='Both';
      NO_IO_CHECK='Both';
      NO_ASSERT_CHECK='TRUE';
      NO_DIR_CHECK='TRUE';
      ALLOW_CONNECT='TRUE';
    'VCCIO1_1':
      PIN_NUMBER='(0,0,0,0,F20,0,0)';
      PINUSE='POWER';
      NO_LOAD_CHECK='Both';
      NO_IO_CHECK='Both';
      NO_ASSERT_CHECK='TRUE';
      NO_DIR_CHECK='TRUE';
      ALLOW_CONNECT='TRUE';
    'VCCIO1_2':
      PIN_NUMBER='(0,0,0,0,J15,0,0)';
      PINUSE='POWER';
      NO_LOAD_CHECK='Both';
      NO_IO_CHECK='Both';
      NO_ASSERT_CHECK='TRUE';
      NO_DIR_CHECK='TRUE';
      ALLOW_CONNECT='TRUE';
    'VCCIO1_3':
      PIN_NUMBER='(0,0,0,0,K15,0,0)';
      PINUSE='POWER';
      NO_LOAD_CHECK='Both';
      NO_IO_CHECK='Both';
      NO_ASSERT_CHECK='TRUE';
      NO_DIR_CHECK='TRUE';
      ALLOW_CONNECT='TRUE';
    'VCCIO1_4':
      PIN_NUMBER='(0,0,0,0,L15,0,0)';
      PINUSE='POWER';
      NO_LOAD_CHECK='Both';
      NO_IO_CHECK='Both';
      NO_ASSERT_CHECK='TRUE';
      NO_DIR_CHECK='TRUE';
      ALLOW_CONNECT='TRUE';
    'VCCIO1_5':
      PIN_NUMBER='(0,0,0,0,M15,0,0)';
      PINUSE='POWER';
      NO_LOAD_CHECK='Both';
      NO_IO_CHECK='Both';
      NO_ASSERT_CHECK='TRUE';
      NO_DIR_CHECK='TRUE';
      ALLOW_CONNECT='TRUE';
    'VCCIO1_6':
      PIN_NUMBER='(0,0,0,0,M18,0,0)';
      PINUSE='POWER';
      NO_LOAD_CHECK='Both';
      NO_IO_CHECK='Both';
      NO_ASSERT_CHECK='TRUE';
      NO_DIR_CHECK='TRUE';
      ALLOW_CONNECT='TRUE';
    'VCCIO1_7':
      PIN_NUMBER='(0,0,0,0,N15,0,0)';
      PINUSE='POWER';
      NO_LOAD_CHECK='Both';
      NO_IO_CHECK='Both';
      NO_ASSERT_CHECK='TRUE';
      NO_DIR_CHECK='TRUE';
      ALLOW_CONNECT='TRUE';
    'VCCIO1_8':
      PIN_NUMBER='(0,0,0,0,P15,0,0)';
      PINUSE='POWER';
      NO_LOAD_CHECK='Both';
      NO_IO_CHECK='Both';
      NO_ASSERT_CHECK='TRUE';
      NO_DIR_CHECK='TRUE';
      ALLOW_CONNECT='TRUE';
    'VCCIO1_9':
      PIN_NUMBER='(0,0,0,0,V20,0,0)';
      PINUSE='POWER';
      NO_LOAD_CHECK='Both';
      NO_IO_CHECK='Both';
      NO_ASSERT_CHECK='TRUE';
      NO_DIR_CHECK='TRUE';
      ALLOW_CONNECT='TRUE';
    'VCCIO0_1':
      PIN_NUMBER='(0,0,0,0,C7,0,0)';
      PINUSE='POWER';
      NO_LOAD_CHECK='Both';
      NO_IO_CHECK='Both';
      NO_ASSERT_CHECK='TRUE';
      NO_DIR_CHECK='TRUE';
      ALLOW_CONNECT='TRUE';
    'VCCIO0_2':
      PIN_NUMBER='(0,0,0,0,C12,0,0)';
      PINUSE='POWER';
      NO_LOAD_CHECK='Both';
      NO_IO_CHECK='Both';
      NO_ASSERT_CHECK='TRUE';
      NO_DIR_CHECK='TRUE';
      ALLOW_CONNECT='TRUE';
    'VCCIO0_3':
      PIN_NUMBER='(0,0,0,0,C16,0,0)';
      PINUSE='POWER';
      NO_LOAD_CHECK='Both';
      NO_IO_CHECK='Both';
      NO_ASSERT_CHECK='TRUE';
      NO_DIR_CHECK='TRUE';
      ALLOW_CONNECT='TRUE';
    'VCCIO0_4':
      PIN_NUMBER='(0,0,0,0,G10,0,0)';
      PINUSE='POWER';
      NO_LOAD_CHECK='Both';
      NO_IO_CHECK='Both';
      NO_ASSERT_CHECK='TRUE';
      NO_DIR_CHECK='TRUE';
      ALLOW_CONNECT='TRUE';
    'VCCIO0_7':
      PIN_NUMBER='(0,0,0,0,H11,0,0)';
      PINUSE='POWER';
      NO_LOAD_CHECK='Both';
      NO_IO_CHECK='Both';
      NO_ASSERT_CHECK='TRUE';
      NO_DIR_CHECK='TRUE';
      ALLOW_CONNECT='TRUE';
    'VCCIO0_8':
      PIN_NUMBER='(0,0,0,0,H12,0,0)';
      PINUSE='POWER';
      NO_LOAD_CHECK='Both';
      NO_IO_CHECK='Both';
      NO_ASSERT_CHECK='TRUE';
      NO_DIR_CHECK='TRUE';
      ALLOW_CONNECT='TRUE';
    'VCCIO0_9':
      PIN_NUMBER='(0,0,0,0,H14,0,0)';
      PINUSE='POWER';
      NO_LOAD_CHECK='Both';
      NO_IO_CHECK='Both';
      NO_ASSERT_CHECK='TRUE';
      NO_DIR_CHECK='TRUE';
      ALLOW_CONNECT='TRUE';
    'VCCIO0_6':
      PIN_NUMBER='(0,0,0,0,H9,0,0)';
      PINUSE='POWER';
      NO_LOAD_CHECK='Both';
      NO_IO_CHECK='Both';
      NO_ASSERT_CHECK='TRUE';
      NO_DIR_CHECK='TRUE';
      ALLOW_CONNECT='TRUE';
    'VCCIO0_5':
      PIN_NUMBER='(0,0,0,0,G13,0,0)';
      PINUSE='POWER';
      NO_LOAD_CHECK='Both';
      NO_IO_CHECK='Both';
      NO_ASSERT_CHECK='TRUE';
      NO_DIR_CHECK='TRUE';
      ALLOW_CONNECT='TRUE';
    'GND1':
      PIN_NUMBER='(0,0,0,0,0,A1,0)';
      PINUSE='POWER';
      NO_LOAD_CHECK='Both';
      NO_IO_CHECK='Both';
      NO_ASSERT_CHECK='TRUE';
      NO_DIR_CHECK='TRUE';
      ALLOW_CONNECT='TRUE';
    'GND2':
      PIN_NUMBER='(0,0,0,0,0,A22,0)';
      PINUSE='POWER';
      NO_LOAD_CHECK='Both';
      NO_IO_CHECK='Both';
      NO_ASSERT_CHECK='TRUE';
      NO_DIR_CHECK='TRUE';
      ALLOW_CONNECT='TRUE';
    'GND3':
      PIN_NUMBER='(0,0,0,0,0,B7,0)';
      PINUSE='POWER';
      NO_LOAD_CHECK='Both';
      NO_IO_CHECK='Both';
      NO_ASSERT_CHECK='TRUE';
      NO_DIR_CHECK='TRUE';
      ALLOW_CONNECT='TRUE';
    'GND4':
      PIN_NUMBER='(0,0,0,0,0,B16,0)';
      PINUSE='POWER';
      NO_LOAD_CHECK='Both';
      NO_IO_CHECK='Both';
      NO_ASSERT_CHECK='TRUE';
      NO_DIR_CHECK='TRUE';
      ALLOW_CONNECT='TRUE';
    'GND5':
      PIN_NUMBER='(0,0,0,0,0,C2,0)';
      PINUSE='POWER';
      NO_LOAD_CHECK='Both';
      NO_IO_CHECK='Both';
      NO_ASSERT_CHECK='TRUE';
      NO_DIR_CHECK='TRUE';
      ALLOW_CONNECT='TRUE';
    'GND6':
      PIN_NUMBER='(0,0,0,0,0,C11,0)';
      PINUSE='POWER';
      NO_LOAD_CHECK='Both';
      NO_IO_CHECK='Both';
      NO_ASSERT_CHECK='TRUE';
      NO_DIR_CHECK='TRUE';
      ALLOW_CONNECT='TRUE';
    'GND7':
      PIN_NUMBER='(0,0,0,0,0,E5,0)';
      PINUSE='POWER';
      NO_LOAD_CHECK='Both';
      NO_IO_CHECK='Both';
      NO_ASSERT_CHECK='TRUE';
      NO_DIR_CHECK='TRUE';
      ALLOW_CONNECT='TRUE';
    'GND8':
      PIN_NUMBER='(0,0,0,0,0,E18,0)';
      PINUSE='POWER';
      NO_LOAD_CHECK='Both';
      NO_IO_CHECK='Both';
      NO_ASSERT_CHECK='TRUE';
      NO_DIR_CHECK='TRUE';
      ALLOW_CONNECT='TRUE';
    'GND9':
      PIN_NUMBER='(0,0,0,0,0,F2,0)';
      PINUSE='POWER';
      NO_LOAD_CHECK='Both';
      NO_IO_CHECK='Both';
      NO_ASSERT_CHECK='TRUE';
      NO_DIR_CHECK='TRUE';
      ALLOW_CONNECT='TRUE';
    'GND10':
      PIN_NUMBER='(0,0,0,0,0,F21,0)';
      PINUSE='POWER';
      NO_LOAD_CHECK='Both';
      NO_IO_CHECK='Both';
      NO_ASSERT_CHECK='TRUE';
      NO_DIR_CHECK='TRUE';
      ALLOW_CONNECT='TRUE';
    'GND11':
      PIN_NUMBER='(0,0,0,0,0,H8,0)';
      PINUSE='POWER';
      NO_LOAD_CHECK='Both';
      NO_IO_CHECK='Both';
      NO_ASSERT_CHECK='TRUE';
      NO_DIR_CHECK='TRUE';
      ALLOW_CONNECT='TRUE';
    'GND12':
      PIN_NUMBER='(0,0,0,0,0,H10,0)';
      PINUSE='POWER';
      NO_LOAD_CHECK='Both';
      NO_IO_CHECK='Both';
      NO_ASSERT_CHECK='TRUE';
      NO_DIR_CHECK='TRUE';
      ALLOW_CONNECT='TRUE';
    'GND13':
      PIN_NUMBER='(0,0,0,0,0,H13,0)';
      PINUSE='POWER';
      NO_LOAD_CHECK='Both';
      NO_IO_CHECK='Both';
      NO_ASSERT_CHECK='TRUE';
      NO_DIR_CHECK='TRUE';
      ALLOW_CONNECT='TRUE';
    'GND14':
      PIN_NUMBER='(0,0,0,0,0,H15,0)';
      PINUSE='POWER';
      NO_LOAD_CHECK='Both';
      NO_IO_CHECK='Both';
      NO_ASSERT_CHECK='TRUE';
      NO_DIR_CHECK='TRUE';
      ALLOW_CONNECT='TRUE';
    'GND15':
      PIN_NUMBER='(0,0,0,0,0,J9,0)';
      PINUSE='POWER';
      NO_LOAD_CHECK='Both';
      NO_IO_CHECK='Both';
      NO_ASSERT_CHECK='TRUE';
      NO_DIR_CHECK='TRUE';
      ALLOW_CONNECT='TRUE';
    'GND16':
      PIN_NUMBER='(0,0,0,0,0,J10,0)';
      PINUSE='POWER';
      NO_LOAD_CHECK='Both';
      NO_IO_CHECK='Both';
      NO_ASSERT_CHECK='TRUE';
      NO_DIR_CHECK='TRUE';
      ALLOW_CONNECT='TRUE';
    'GND17':
      PIN_NUMBER='(0,0,0,0,0,J11,0)';
      PINUSE='POWER';
      NO_LOAD_CHECK='Both';
      NO_IO_CHECK='Both';
      NO_ASSERT_CHECK='TRUE';
      NO_DIR_CHECK='TRUE';
      ALLOW_CONNECT='TRUE';
    'GND18':
      PIN_NUMBER='(0,0,0,0,0,J12,0)';
      PINUSE='POWER';
      NO_LOAD_CHECK='Both';
      NO_IO_CHECK='Both';
      NO_ASSERT_CHECK='TRUE';
      NO_DIR_CHECK='TRUE';
      ALLOW_CONNECT='TRUE';
    'GND19':
      PIN_NUMBER='(0,0,0,0,0,J13,0)';
      PINUSE='POWER';
      NO_LOAD_CHECK='Both';
      NO_IO_CHECK='Both';
      NO_ASSERT_CHECK='TRUE';
      NO_DIR_CHECK='TRUE';
      ALLOW_CONNECT='TRUE';
    'GND20':
      PIN_NUMBER='(0,0,0,0,0,J14,0)';
      PINUSE='POWER';
      NO_LOAD_CHECK='Both';
      NO_IO_CHECK='Both';
      NO_ASSERT_CHECK='TRUE';
      NO_DIR_CHECK='TRUE';
      ALLOW_CONNECT='TRUE';
    'GND21':
      PIN_NUMBER='(0,0,0,0,0,K9,0)';
      PINUSE='POWER';
      NO_LOAD_CHECK='Both';
      NO_IO_CHECK='Both';
      NO_ASSERT_CHECK='TRUE';
      NO_DIR_CHECK='TRUE';
      ALLOW_CONNECT='TRUE';
    'GND22':
      PIN_NUMBER='(0,0,0,0,0,K14,0)';
      PINUSE='POWER';
      NO_LOAD_CHECK='Both';
      NO_IO_CHECK='Both';
      NO_ASSERT_CHECK='TRUE';
      NO_DIR_CHECK='TRUE';
      ALLOW_CONNECT='TRUE';
    'GND23':
      PIN_NUMBER='(0,0,0,0,0,K21,0)';
      PINUSE='POWER';
      NO_LOAD_CHECK='Both';
      NO_IO_CHECK='Both';
      NO_ASSERT_CHECK='TRUE';
      NO_DIR_CHECK='TRUE';
      ALLOW_CONNECT='TRUE';
    'GND24':
      PIN_NUMBER='(0,0,0,0,0,L2,0)';
      PINUSE='POWER';
      NO_LOAD_CHECK='Both';
      NO_IO_CHECK='Both';
      NO_ASSERT_CHECK='TRUE';
      NO_DIR_CHECK='TRUE';
      ALLOW_CONNECT='TRUE';
    'GND25':
      PIN_NUMBER='(0,0,0,0,0,L9,0)';
      PINUSE='POWER';
      NO_LOAD_CHECK='Both';
      NO_IO_CHECK='Both';
      NO_ASSERT_CHECK='TRUE';
      NO_DIR_CHECK='TRUE';
      ALLOW_CONNECT='TRUE';
    'GND26':
      PIN_NUMBER='(0,0,0,0,0,L10,0)';
      PINUSE='POWER';
      NO_LOAD_CHECK='Both';
      NO_IO_CHECK='Both';
      NO_ASSERT_CHECK='TRUE';
      NO_DIR_CHECK='TRUE';
      ALLOW_CONNECT='TRUE';
    'GND27':
      PIN_NUMBER='(0,0,0,0,0,L13,0)';
      PINUSE='POWER';
      NO_LOAD_CHECK='Both';
      NO_IO_CHECK='Both';
      NO_ASSERT_CHECK='TRUE';
      NO_DIR_CHECK='TRUE';
      ALLOW_CONNECT='TRUE';
    'GND28':
      PIN_NUMBER='(0,0,0,0,0,L14,0)';
      PINUSE='POWER';
      NO_LOAD_CHECK='Both';
      NO_IO_CHECK='Both';
      NO_ASSERT_CHECK='TRUE';
      NO_DIR_CHECK='TRUE';
      ALLOW_CONNECT='TRUE';
    'GND29':
      PIN_NUMBER='(0,0,0,0,0,L18,0)';
      PINUSE='POWER';
      NO_LOAD_CHECK='Both';
      NO_IO_CHECK='Both';
      NO_ASSERT_CHECK='TRUE';
      NO_DIR_CHECK='TRUE';
      ALLOW_CONNECT='TRUE';
    'GND30':
      PIN_NUMBER='(0,0,0,0,0,M4,0)';
      PINUSE='POWER';
      NO_LOAD_CHECK='Both';
      NO_IO_CHECK='Both';
      NO_ASSERT_CHECK='TRUE';
      NO_DIR_CHECK='TRUE';
      ALLOW_CONNECT='TRUE';
    'GND31':
      PIN_NUMBER='(0,0,0,0,0,M9,0)';
      PINUSE='POWER';
      NO_LOAD_CHECK='Both';
      NO_IO_CHECK='Both';
      NO_ASSERT_CHECK='TRUE';
      NO_DIR_CHECK='TRUE';
      ALLOW_CONNECT='TRUE';
    'GND32':
      PIN_NUMBER='(0,0,0,0,0,M10,0)';
      PINUSE='POWER';
      NO_LOAD_CHECK='Both';
      NO_IO_CHECK='Both';
      NO_ASSERT_CHECK='TRUE';
      NO_DIR_CHECK='TRUE';
      ALLOW_CONNECT='TRUE';
    'GND33':
      PIN_NUMBER='(0,0,0,0,0,M13,0)';
      PINUSE='POWER';
      NO_LOAD_CHECK='Both';
      NO_IO_CHECK='Both';
      NO_ASSERT_CHECK='TRUE';
      NO_DIR_CHECK='TRUE';
      ALLOW_CONNECT='TRUE';
    'GND34':
      PIN_NUMBER='(0,0,0,0,0,M14,0)';
      PINUSE='POWER';
      NO_LOAD_CHECK='Both';
      NO_IO_CHECK='Both';
      NO_ASSERT_CHECK='TRUE';
      NO_DIR_CHECK='TRUE';
      ALLOW_CONNECT='TRUE';
    'GND35':
      PIN_NUMBER='(0,0,0,0,0,N9,0)';
      PINUSE='POWER';
      NO_LOAD_CHECK='Both';
      NO_IO_CHECK='Both';
      NO_ASSERT_CHECK='TRUE';
      NO_DIR_CHECK='TRUE';
      ALLOW_CONNECT='TRUE';
    'GND36':
      PIN_NUMBER='(0,0,0,0,0,N14,0)';
      PINUSE='POWER';
      NO_LOAD_CHECK='Both';
      NO_IO_CHECK='Both';
      NO_ASSERT_CHECK='TRUE';
      NO_DIR_CHECK='TRUE';
      ALLOW_CONNECT='TRUE';
    'GND37':
      PIN_NUMBER='(0,0,0,0,0,N21,0)';
      PINUSE='POWER';
      NO_LOAD_CHECK='Both';
      NO_IO_CHECK='Both';
      NO_ASSERT_CHECK='TRUE';
      NO_DIR_CHECK='TRUE';
      ALLOW_CONNECT='TRUE';
    'GND38':
      PIN_NUMBER='(0,0,0,0,0,P9,0)';
      PINUSE='POWER';
      NO_LOAD_CHECK='Both';
      NO_IO_CHECK='Both';
      NO_ASSERT_CHECK='TRUE';
      NO_DIR_CHECK='TRUE';
      ALLOW_CONNECT='TRUE';
    'GND39':
      PIN_NUMBER='(0,0,0,0,0,P10,0)';
      PINUSE='POWER';
      NO_LOAD_CHECK='Both';
      NO_IO_CHECK='Both';
      NO_ASSERT_CHECK='TRUE';
      NO_DIR_CHECK='TRUE';
      ALLOW_CONNECT='TRUE';
    'GND40':
      PIN_NUMBER='(0,0,0,0,0,P11,0)';
      PINUSE='POWER';
      NO_LOAD_CHECK='Both';
      NO_IO_CHECK='Both';
      NO_ASSERT_CHECK='TRUE';
      NO_DIR_CHECK='TRUE';
      ALLOW_CONNECT='TRUE';
    'GND41':
      PIN_NUMBER='(0,0,0,0,0,P12,0)';
      PINUSE='POWER';
      NO_LOAD_CHECK='Both';
      NO_IO_CHECK='Both';
      NO_ASSERT_CHECK='TRUE';
      NO_DIR_CHECK='TRUE';
      ALLOW_CONNECT='TRUE';
    'GND42':
      PIN_NUMBER='(0,0,0,0,0,P13,0)';
      PINUSE='POWER';
      NO_LOAD_CHECK='Both';
      NO_IO_CHECK='Both';
      NO_ASSERT_CHECK='TRUE';
      NO_DIR_CHECK='TRUE';
      ALLOW_CONNECT='TRUE';
    'GND43':
      PIN_NUMBER='(0,0,0,0,0,P14,0)';
      PINUSE='POWER';
      NO_LOAD_CHECK='Both';
      NO_IO_CHECK='Both';
      NO_ASSERT_CHECK='TRUE';
      NO_DIR_CHECK='TRUE';
      ALLOW_CONNECT='TRUE';
    'GND44':
      PIN_NUMBER='(0,0,0,0,0,R8,0)';
      PINUSE='POWER';
      NO_LOAD_CHECK='Both';
      NO_IO_CHECK='Both';
      NO_ASSERT_CHECK='TRUE';
      NO_DIR_CHECK='TRUE';
      ALLOW_CONNECT='TRUE';
    'GND45':
      PIN_NUMBER='(0,0,0,0,0,R15,0)';
      PINUSE='POWER';
      NO_LOAD_CHECK='Both';
      NO_IO_CHECK='Both';
      NO_ASSERT_CHECK='TRUE';
      NO_DIR_CHECK='TRUE';
      ALLOW_CONNECT='TRUE';
    'GND46':
      PIN_NUMBER='(0,0,0,0,0,V2,0)';
      PINUSE='POWER';
      NO_LOAD_CHECK='Both';
      NO_IO_CHECK='Both';
      NO_ASSERT_CHECK='TRUE';
      NO_DIR_CHECK='TRUE';
      ALLOW_CONNECT='TRUE';
    'GND47':
      PIN_NUMBER='(0,0,0,0,0,V21,0)';
      PINUSE='POWER';
      NO_LOAD_CHECK='Both';
      NO_IO_CHECK='Both';
      NO_ASSERT_CHECK='TRUE';
      NO_DIR_CHECK='TRUE';
      ALLOW_CONNECT='TRUE';
    'GND48':
      PIN_NUMBER='(0,0,0,0,0,W12,0)';
      PINUSE='POWER';
      NO_LOAD_CHECK='Both';
      NO_IO_CHECK='Both';
      NO_ASSERT_CHECK='TRUE';
      NO_DIR_CHECK='TRUE';
      ALLOW_CONNECT='TRUE';
    'GND50':
      PIN_NUMBER='(0,0,0,0,0,Y16,0)';
      PINUSE='POWER';
      NO_LOAD_CHECK='Both';
      NO_IO_CHECK='Both';
      NO_ASSERT_CHECK='TRUE';
      NO_DIR_CHECK='TRUE';
      ALLOW_CONNECT='TRUE';
    'GND49':
      PIN_NUMBER='(0,0,0,0,0,Y7,0)';
      PINUSE='POWER';
      NO_LOAD_CHECK='Both';
      NO_IO_CHECK='Both';
      NO_ASSERT_CHECK='TRUE';
      NO_DIR_CHECK='TRUE';
      ALLOW_CONNECT='TRUE';
    'GND51':
      PIN_NUMBER='(0,0,0,0,0,AB1,0)';
      PINUSE='POWER';
      NO_LOAD_CHECK='Both';
      NO_IO_CHECK='Both';
      NO_ASSERT_CHECK='TRUE';
      NO_DIR_CHECK='TRUE';
      ALLOW_CONNECT='TRUE';
    'GND52':
      PIN_NUMBER='(0,0,0,0,0,AB22,0)';
      PINUSE='POWER';
      NO_LOAD_CHECK='Both';
      NO_IO_CHECK='Both';
      NO_ASSERT_CHECK='TRUE';
      NO_DIR_CHECK='TRUE';
      ALLOW_CONNECT='TRUE';
    'PR30B':
      PIN_NUMBER='(0,0,0,0,0,0,W20)';
      BIDIRECTIONAL='TRUE';
      INPUT_LOAD='(-0.01,0.01)';
      OUTPUT_LOAD='(1.0,-1.0)';
    'PR30A':
      PIN_NUMBER='(0,0,0,0,0,0,V18)';
      BIDIRECTIONAL='TRUE';
      INPUT_LOAD='(-0.01,0.01)';
      OUTPUT_LOAD='(1.0,-1.0)';
    'PR29D':
      PIN_NUMBER='(0,0,0,0,0,0,V19)';
      BIDIRECTIONAL='TRUE';
      INPUT_LOAD='(-0.01,0.01)';
      OUTPUT_LOAD='(1.0,-1.0)';
    'PR29B':
      PIN_NUMBER='(0,0,0,0,0,0,Y21)';
      BIDIRECTIONAL='TRUE';
      INPUT_LOAD='(-0.01,0.01)';
      OUTPUT_LOAD='(1.0,-1.0)';
    'PR29C':
      PIN_NUMBER='(0,0,0,0,0,0,U17)';
      BIDIRECTIONAL='TRUE';
      INPUT_LOAD='(-0.01,0.01)';
      OUTPUT_LOAD='(1.0,-1.0)';
    'PR29A':
      PIN_NUMBER='(0,0,0,0,0,0,AA22)';
      BIDIRECTIONAL='TRUE';
      INPUT_LOAD='(-0.01,0.01)';
      OUTPUT_LOAD='(1.0,-1.0)';
    'PR25B':
      PIN_NUMBER='(0,0,0,0,0,0,W22)';
      BIDIRECTIONAL='TRUE';
      INPUT_LOAD='(-0.01,0.01)';
      OUTPUT_LOAD='(1.0,-1.0)';
    'PR25A':
      PIN_NUMBER='(0,0,0,0,0,0,V22)';
      BIDIRECTIONAL='TRUE';
      INPUT_LOAD='(-0.01,0.01)';
      OUTPUT_LOAD='(1.0,-1.0)';
    'PR20B':
      PIN_NUMBER='(0,0,0,0,0,0,R21)';
      BIDIRECTIONAL='TRUE';
      INPUT_LOAD='(-0.01,0.01)';
      OUTPUT_LOAD='(1.0,-1.0)';
    'PR20A':
      PIN_NUMBER='(0,0,0,0,0,0,R22)';
      BIDIRECTIONAL='TRUE';
      INPUT_LOAD='(-0.01,0.01)';
      OUTPUT_LOAD='(1.0,-1.0)';
    'PR19B':
      PIN_NUMBER='(0,0,0,0,0,0,P21)';
      BIDIRECTIONAL='TRUE';
      INPUT_LOAD='(-0.01,0.01)';
      OUTPUT_LOAD='(1.0,-1.0)';
    'PR19A':
      PIN_NUMBER='(0,0,0,0,0,0,N22)';
      BIDIRECTIONAL='TRUE';
      INPUT_LOAD='(-0.01,0.01)';
      OUTPUT_LOAD='(1.0,-1.0)';
    'PR17B||PCLKC1_0':
      PIN_NUMBER='(0,0,0,0,0,0,M21)';
      BIDIRECTIONAL='TRUE';
      INPUT_LOAD='(-0.01,0.01)';
      OUTPUT_LOAD='(1.0,-1.0)';
    'PR17A||PCLKT1_0':
      PIN_NUMBER='(0,0,0,0,0,0,M22)';
      BIDIRECTIONAL='TRUE';
      INPUT_LOAD='(-0.01,0.01)';
      OUTPUT_LOAD='(1.0,-1.0)';
    'PR16B':
      PIN_NUMBER='(0,0,0,0,0,0,L21)';
      BIDIRECTIONAL='TRUE';
      INPUT_LOAD='(-0.01,0.01)';
      OUTPUT_LOAD='(1.0,-1.0)';
    'PR16A':
      PIN_NUMBER='(0,0,0,0,0,0,K22)';
      BIDIRECTIONAL='TRUE';
      INPUT_LOAD='(-0.01,0.01)';
      OUTPUT_LOAD='(1.0,-1.0)';
    'PR14B':
      PIN_NUMBER='(0,0,0,0,0,0,L16)';
      BIDIRECTIONAL='TRUE';
      INPUT_LOAD='(-0.01,0.01)';
      OUTPUT_LOAD='(1.0,-1.0)';
    'PR14A':
      PIN_NUMBER='(0,0,0,0,0,0,L17)';
      BIDIRECTIONAL='TRUE';
      INPUT_LOAD='(-0.01,0.01)';
      OUTPUT_LOAD='(1.0,-1.0)';
    'PR7B':
      PIN_NUMBER='(0,0,0,0,0,0,H21)';
      BIDIRECTIONAL='TRUE';
      INPUT_LOAD='(-0.01,0.01)';
      OUTPUT_LOAD='(1.0,-1.0)';
    'PR7A':
      PIN_NUMBER='(0,0,0,0,0,0,H22)';
      BIDIRECTIONAL='TRUE';
      INPUT_LOAD='(-0.01,0.01)';
      OUTPUT_LOAD='(1.0,-1.0)';
    'PR3B||R_GPLLC_IN':
      PIN_NUMBER='(0,0,0,0,0,0,D21)';
      BIDIRECTIONAL='TRUE';
      INPUT_LOAD='(-0.01,0.01)';
      OUTPUT_LOAD='(1.0,-1.0)';
    'PR3A||R_GPLLT_IN':
      PIN_NUMBER='(0,0,0,0,0,0,D22)';
      BIDIRECTIONAL='TRUE';
      INPUT_LOAD='(-0.01,0.01)';
      OUTPUT_LOAD='(1.0,-1.0)';
    'PR2B||R_GPLLC_FB':
      PIN_NUMBER='(0,0,0,0,0,0,C22)';
      BIDIRECTIONAL='TRUE';
      INPUT_LOAD='(-0.01,0.01)';
      OUTPUT_LOAD='(1.0,-1.0)';
    'PR2A||R_GPLLT_FB':
      PIN_NUMBER='(0,0,0,0,0,0,C21)';
      BIDIRECTIONAL='TRUE';
      INPUT_LOAD='(-0.01,0.01)';
      OUTPUT_LOAD='(1.0,-1.0)';
    'PR2C':
      PIN_NUMBER='(0,0,0,0,0,0,F17)';
      BIDIRECTIONAL='TRUE';
      INPUT_LOAD='(-0.01,0.01)';
      OUTPUT_LOAD='(1.0,-1.0)';
    'PR2D':
      PIN_NUMBER='(0,0,0,0,0,0,G16)';
      BIDIRECTIONAL='TRUE';
      INPUT_LOAD='(-0.01,0.01)';
      OUTPUT_LOAD='(1.0,-1.0)';
    'PR3C':
      PIN_NUMBER='(0,0,0,0,0,0,D19)';
      BIDIRECTIONAL='TRUE';
      INPUT_LOAD='(-0.01,0.01)';
      OUTPUT_LOAD='(1.0,-1.0)';
    'PR3D':
      PIN_NUMBER='(0,0,0,0,0,0,D20)';
      BIDIRECTIONAL='TRUE';
      INPUT_LOAD='(-0.01,0.01)';
      OUTPUT_LOAD='(1.0,-1.0)';
    'PR4C':
      PIN_NUMBER='(0,0,0,0,0,0,E19)';
      BIDIRECTIONAL='TRUE';
      INPUT_LOAD='(-0.01,0.01)';
      OUTPUT_LOAD='(1.0,-1.0)';
    'PR4D':
      PIN_NUMBER='(0,0,0,0,0,0,E20)';
      BIDIRECTIONAL='TRUE';
      INPUT_LOAD='(-0.01,0.01)';
      OUTPUT_LOAD='(1.0,-1.0)';
    'PR4A':
      PIN_NUMBER='(0,0,0,0,0,0,E22)';
      BIDIRECTIONAL='TRUE';
      INPUT_LOAD='(-0.01,0.01)';
      OUTPUT_LOAD='(1.0,-1.0)';
    'PR4B':
      PIN_NUMBER='(0,0,0,0,0,0,E21)';
      BIDIRECTIONAL='TRUE';
      INPUT_LOAD='(-0.01,0.01)';
      OUTPUT_LOAD='(1.0,-1.0)';
    'PR5A':
      PIN_NUMBER='(0,0,0,0,0,0,F22)';
      BIDIRECTIONAL='TRUE';
      INPUT_LOAD='(-0.01,0.01)';
      OUTPUT_LOAD='(1.0,-1.0)';
    'PR5B':
      PIN_NUMBER='(0,0,0,0,0,0,G22)';
      BIDIRECTIONAL='TRUE';
      INPUT_LOAD='(-0.01,0.01)';
      OUTPUT_LOAD='(1.0,-1.0)';
    'PR5C':
      PIN_NUMBER='(0,0,0,0,0,0,F18)';
      BIDIRECTIONAL='TRUE';
      INPUT_LOAD='(-0.01,0.01)';
      OUTPUT_LOAD='(1.0,-1.0)';
    'PR5D':
      PIN_NUMBER='(0,0,0,0,0,0,F19)';
      BIDIRECTIONAL='TRUE';
      INPUT_LOAD='(-0.01,0.01)';
      OUTPUT_LOAD='(1.0,-1.0)';
    'PR6A':
      PIN_NUMBER='(0,0,0,0,0,0,G21)';
      BIDIRECTIONAL='TRUE';
      INPUT_LOAD='(-0.01,0.01)';
      OUTPUT_LOAD='(1.0,-1.0)';
    'PR6B':
      PIN_NUMBER='(0,0,0,0,0,0,G20)';
      BIDIRECTIONAL='TRUE';
      INPUT_LOAD='(-0.01,0.01)';
      OUTPUT_LOAD='(1.0,-1.0)';
    'PR6C':
      PIN_NUMBER='(0,0,0,0,0,0,G19)';
      BIDIRECTIONAL='TRUE';
      INPUT_LOAD='(-0.01,0.01)';
      OUTPUT_LOAD='(1.0,-1.0)';
    'PR6D':
      PIN_NUMBER='(0,0,0,0,0,0,G18)';
      BIDIRECTIONAL='TRUE';
      INPUT_LOAD='(-0.01,0.01)';
      OUTPUT_LOAD='(1.0,-1.0)';
    'PR7C':
      PIN_NUMBER='(0,0,0,0,0,0,G17)';
      BIDIRECTIONAL='TRUE';
      INPUT_LOAD='(-0.01,0.01)';
      OUTPUT_LOAD='(1.0,-1.0)';
    'PR7D':
      PIN_NUMBER='(0,0,0,0,0,0,H20)';
      BIDIRECTIONAL='TRUE';
      INPUT_LOAD='(-0.01,0.01)';
      OUTPUT_LOAD='(1.0,-1.0)';
    'PR10A':
      PIN_NUMBER='(0,0,0,0,0,0,H19)';
      BIDIRECTIONAL='TRUE';
      INPUT_LOAD='(-0.01,0.01)';
      OUTPUT_LOAD='(1.0,-1.0)';
    'PR10B':
      PIN_NUMBER='(0,0,0,0,0,0,H18)';
      BIDIRECTIONAL='TRUE';
      INPUT_LOAD='(-0.01,0.01)';
      OUTPUT_LOAD='(1.0,-1.0)';
    'PR10C':
      PIN_NUMBER='(0,0,0,0,0,0,H17)';
      BIDIRECTIONAL='TRUE';
      INPUT_LOAD='(-0.01,0.01)';
      OUTPUT_LOAD='(1.0,-1.0)';
    'PR10D':
      PIN_NUMBER='(0,0,0,0,0,0,H16)';
      BIDIRECTIONAL='TRUE';
      INPUT_LOAD='(-0.01,0.01)';
      OUTPUT_LOAD='(1.0,-1.0)';
    'PR11A':
      PIN_NUMBER='(0,0,0,0,0,0,J16)';
      BIDIRECTIONAL='TRUE';
      INPUT_LOAD='(-0.01,0.01)';
      OUTPUT_LOAD='(1.0,-1.0)';
    'PR11B':
      PIN_NUMBER='(0,0,0,0,0,0,J17)';
      BIDIRECTIONAL='TRUE';
      INPUT_LOAD='(-0.01,0.01)';
      OUTPUT_LOAD='(1.0,-1.0)';
    'PR11C':
      PIN_NUMBER='(0,0,0,0,0,0,J18)';
      BIDIRECTIONAL='TRUE';
      INPUT_LOAD='(-0.01,0.01)';
      OUTPUT_LOAD='(1.0,-1.0)';
    'PR11D':
      PIN_NUMBER='(0,0,0,0,0,0,J19)';
      BIDIRECTIONAL='TRUE';
      INPUT_LOAD='(-0.01,0.01)';
      OUTPUT_LOAD='(1.0,-1.0)';
    'PR12A':
      PIN_NUMBER='(0,0,0,0,0,0,J21)';
      BIDIRECTIONAL='TRUE';
      INPUT_LOAD='(-0.01,0.01)';
      OUTPUT_LOAD='(1.0,-1.0)';
    'PR12B':
      PIN_NUMBER='(0,0,0,0,0,0,J22)';
      BIDIRECTIONAL='TRUE';
      INPUT_LOAD='(-0.01,0.01)';
      OUTPUT_LOAD='(1.0,-1.0)';
    'PR12C':
      PIN_NUMBER='(0,0,0,0,0,0,J20)';
      BIDIRECTIONAL='TRUE';
      INPUT_LOAD='(-0.01,0.01)';
      OUTPUT_LOAD='(1.0,-1.0)';
    'PR12D':
      PIN_NUMBER='(0,0,0,0,0,0,K20)';
      BIDIRECTIONAL='TRUE';
      INPUT_LOAD='(-0.01,0.01)';
      OUTPUT_LOAD='(1.0,-1.0)';
    'PR13A':
      PIN_NUMBER='(0,0,0,0,0,0,K19)';
      BIDIRECTIONAL='TRUE';
      INPUT_LOAD='(-0.01,0.01)';
      OUTPUT_LOAD='(1.0,-1.0)';
    'PR13B':
      PIN_NUMBER='(0,0,0,0,0,0,K18)';
      BIDIRECTIONAL='TRUE';
      INPUT_LOAD='(-0.01,0.01)';
      OUTPUT_LOAD='(1.0,-1.0)';
    'PR13C':
      PIN_NUMBER='(0,0,0,0,0,0,K17)';
      BIDIRECTIONAL='TRUE';
      INPUT_LOAD='(-0.01,0.01)';
      OUTPUT_LOAD='(1.0,-1.0)';
    'PR13D':
      PIN_NUMBER='(0,0,0,0,0,0,K16)';
      BIDIRECTIONAL='TRUE';
      INPUT_LOAD='(-0.01,0.01)';
      OUTPUT_LOAD='(1.0,-1.0)';
    'PR14C':
      PIN_NUMBER='(0,0,0,0,0,0,L19)';
      BIDIRECTIONAL='TRUE';
      INPUT_LOAD='(-0.01,0.01)';
      OUTPUT_LOAD='(1.0,-1.0)';
    'PR14D':
      PIN_NUMBER='(0,0,0,0,0,0,L20)';
      BIDIRECTIONAL='TRUE';
      INPUT_LOAD='(-0.01,0.01)';
      OUTPUT_LOAD='(1.0,-1.0)';
    'PR16C':
      PIN_NUMBER='(0,0,0,0,0,0,L22)';
      BIDIRECTIONAL='TRUE';
      INPUT_LOAD='(-0.01,0.01)';
      OUTPUT_LOAD='(1.0,-1.0)';
    'PR16D':
      PIN_NUMBER='(0,0,0,0,0,0,M17)';
      BIDIRECTIONAL='TRUE';
      INPUT_LOAD='(-0.01,0.01)';
      OUTPUT_LOAD='(1.0,-1.0)';
    'PR17C':
      PIN_NUMBER='(0,0,0,0,0,0,M20)';
      BIDIRECTIONAL='TRUE';
      INPUT_LOAD='(-0.01,0.01)';
      OUTPUT_LOAD='(1.0,-1.0)';
    'PR17D':
      PIN_NUMBER='(0,0,0,0,0,0,M19)';
      BIDIRECTIONAL='TRUE';
      INPUT_LOAD='(-0.01,0.01)';
      OUTPUT_LOAD='(1.0,-1.0)';
    'PR18A':
      PIN_NUMBER='(0,0,0,0,0,0,M16)';
      BIDIRECTIONAL='TRUE';
      INPUT_LOAD='(-0.01,0.01)';
      OUTPUT_LOAD='(1.0,-1.0)';
    'PR18B':
      PIN_NUMBER='(0,0,0,0,0,0,N16)';
      BIDIRECTIONAL='TRUE';
      INPUT_LOAD='(-0.01,0.01)';
      OUTPUT_LOAD='(1.0,-1.0)';
    'PR18C':
      PIN_NUMBER='(0,0,0,0,0,0,N17)';
      BIDIRECTIONAL='TRUE';
      INPUT_LOAD='(-0.01,0.01)';
      OUTPUT_LOAD='(1.0,-1.0)';
    'PR18D':
      PIN_NUMBER='(0,0,0,0,0,0,N18)';
      BIDIRECTIONAL='TRUE';
      INPUT_LOAD='(-0.01,0.01)';
      OUTPUT_LOAD='(1.0,-1.0)';
    'PR19C':
      PIN_NUMBER='(0,0,0,0,0,0,N20)';
      BIDIRECTIONAL='TRUE';
      INPUT_LOAD='(-0.01,0.01)';
      OUTPUT_LOAD='(1.0,-1.0)';
    'PR19D':
      PIN_NUMBER='(0,0,0,0,0,0,N19)';
      BIDIRECTIONAL='TRUE';
      INPUT_LOAD='(-0.01,0.01)';
      OUTPUT_LOAD='(1.0,-1.0)';
    'PR20C':
      PIN_NUMBER='(0,0,0,0,0,0,P22)';
      BIDIRECTIONAL='TRUE';
      INPUT_LOAD='(-0.01,0.01)';
      OUTPUT_LOAD='(1.0,-1.0)';
    'PR20D':
      PIN_NUMBER='(0,0,0,0,0,0,P20)';
      BIDIRECTIONAL='TRUE';
      INPUT_LOAD='(-0.01,0.01)';
      OUTPUT_LOAD='(1.0,-1.0)';
    'PR21A':
      PIN_NUMBER='(0,0,0,0,0,0,T22)';
      BIDIRECTIONAL='TRUE';
      INPUT_LOAD='(-0.01,0.01)';
      OUTPUT_LOAD='(1.0,-1.0)';
    'PR21B':
      PIN_NUMBER='(0,0,0,0,0,0,T21)';
      BIDIRECTIONAL='TRUE';
      INPUT_LOAD='(-0.01,0.01)';
      OUTPUT_LOAD='(1.0,-1.0)';
    'PR21C':
      PIN_NUMBER='(0,0,0,0,0,0,P19)';
      BIDIRECTIONAL='TRUE';
      INPUT_LOAD='(-0.01,0.01)';
      OUTPUT_LOAD='(1.0,-1.0)';
    'PR21D':
      PIN_NUMBER='(0,0,0,0,0,0,P18)';
      BIDIRECTIONAL='TRUE';
      INPUT_LOAD='(-0.01,0.01)';
      OUTPUT_LOAD='(1.0,-1.0)';
    'PR24A':
      PIN_NUMBER='(0,0,0,0,0,0,P17)';
      BIDIRECTIONAL='TRUE';
      INPUT_LOAD='(-0.01,0.01)';
      OUTPUT_LOAD='(1.0,-1.0)';
    'PR24B':
      PIN_NUMBER='(0,0,0,0,0,0,P16)';
      BIDIRECTIONAL='TRUE';
      INPUT_LOAD='(-0.01,0.01)';
      OUTPUT_LOAD='(1.0,-1.0)';
    'PR24C':
      PIN_NUMBER='(0,0,0,0,0,0,U22)';
      BIDIRECTIONAL='TRUE';
      INPUT_LOAD='(-0.01,0.01)';
      OUTPUT_LOAD='(1.0,-1.0)';
    'PR24D':
      PIN_NUMBER='(0,0,0,0,0,0,U21)';
      BIDIRECTIONAL='TRUE';
      INPUT_LOAD='(-0.01,0.01)';
      OUTPUT_LOAD='(1.0,-1.0)';
    'PR25C':
      PIN_NUMBER='(0,0,0,0,0,0,R20)';
      BIDIRECTIONAL='TRUE';
      INPUT_LOAD='(-0.01,0.01)';
      OUTPUT_LOAD='(1.0,-1.0)';
    'PR25D':
      PIN_NUMBER='(0,0,0,0,0,0,R19)';
      BIDIRECTIONAL='TRUE';
      INPUT_LOAD='(-0.01,0.01)';
      OUTPUT_LOAD='(1.0,-1.0)';
    'PR26A':
      PIN_NUMBER='(0,0,0,0,0,0,R18)';
      BIDIRECTIONAL='TRUE';
      INPUT_LOAD='(-0.01,0.01)';
      OUTPUT_LOAD='(1.0,-1.0)';
    'PR26B':
      PIN_NUMBER='(0,0,0,0,0,0,R17)';
      BIDIRECTIONAL='TRUE';
      INPUT_LOAD='(-0.01,0.01)';
      OUTPUT_LOAD='(1.0,-1.0)';
    'PR26C':
      PIN_NUMBER='(0,0,0,0,0,0,R16)';
      BIDIRECTIONAL='TRUE';
      INPUT_LOAD='(-0.01,0.01)';
      OUTPUT_LOAD='(1.0,-1.0)';
    'PR26D':
      PIN_NUMBER='(0,0,0,0,0,0,T20)';
      BIDIRECTIONAL='TRUE';
      INPUT_LOAD='(-0.01,0.01)';
      OUTPUT_LOAD='(1.0,-1.0)';
    'PR27A':
      PIN_NUMBER='(0,0,0,0,0,0,T19)';
      BIDIRECTIONAL='TRUE';
      INPUT_LOAD='(-0.01,0.01)';
      OUTPUT_LOAD='(1.0,-1.0)';
    'PR27B':
      PIN_NUMBER='(0,0,0,0,0,0,T18)';
      BIDIRECTIONAL='TRUE';
      INPUT_LOAD='(-0.01,0.01)';
      OUTPUT_LOAD='(1.0,-1.0)';
    'PR27C':
      PIN_NUMBER='(0,0,0,0,0,0,T17)';
      BIDIRECTIONAL='TRUE';
      INPUT_LOAD='(-0.01,0.01)';
      OUTPUT_LOAD='(1.0,-1.0)';
    'PR27D':
      PIN_NUMBER='(0,0,0,0,0,0,U20)';
      BIDIRECTIONAL='TRUE';
      INPUT_LOAD='(-0.01,0.01)';
      OUTPUT_LOAD='(1.0,-1.0)';
    'PR28A':
      PIN_NUMBER='(0,0,0,0,0,0,Y22)';
      BIDIRECTIONAL='TRUE';
      INPUT_LOAD='(-0.01,0.01)';
      OUTPUT_LOAD='(1.0,-1.0)';
    'PR28B':
      PIN_NUMBER='(0,0,0,0,0,0,W21)';
      BIDIRECTIONAL='TRUE';
      INPUT_LOAD='(-0.01,0.01)';
      OUTPUT_LOAD='(1.0,-1.0)';
    'PR28C':
      PIN_NUMBER='(0,0,0,0,0,0,U19)';
      BIDIRECTIONAL='TRUE';
      INPUT_LOAD='(-0.01,0.01)';
      OUTPUT_LOAD='(1.0,-1.0)';
    'PR28D':
      PIN_NUMBER='(0,0,0,0,0,0,U18)';
      BIDIRECTIONAL='TRUE';
      INPUT_LOAD='(-0.01,0.01)';
      OUTPUT_LOAD='(1.0,-1.0)';
    'PR30C':
      PIN_NUMBER='(0,0,0,0,0,0,W19)';
      BIDIRECTIONAL='TRUE';
      INPUT_LOAD='(-0.01,0.01)';
      OUTPUT_LOAD='(1.0,-1.0)';
    'PR30D':
      PIN_NUMBER='(0,0,0,0,0,0,Y20)';
      BIDIRECTIONAL='TRUE';
      INPUT_LOAD='(-0.01,0.01)';
      OUTPUT_LOAD='(1.0,-1.0)';
  end_pin;
  body
    PART_NAME='LCMXO3LF9400C5BG484C';
    BODY_NAME='LCMXO3LF9400C5BG484C';
    PHYS_DES_PREFIX='U';
    CLASS='IC';
  end_body;
end_primitive;

END.
